FILE_TYPE = MACRO_DRAWING;
SET COLOR_WIRE YELLOW;
SET COLOR_PROP MONO;
SET COLOR_DOT WHITE;
SET COLOR_ARC YELLOW;
SET COLOR_BODY GREEN;
SET COLOR_NOTE MONO;
SET PROP_DISPLAY VALUE;
SET PAGE_NUMBER P94;
FORCEADD RES..2
R 2
(-300 3650);
FORCEPROP 1 LAST LOCATION R4U2
J 2
(-345 3775);
DISPLAY 0.617021 (-345 3775);
PAINT AQUA (-345 3775);
FORCEPROP 1 LAST PART_NUMBER G21796-112
J 2
(-340 3525);
DISPLAY 0.617021 (-340 3525);
PAINT BLUE (-340 3525);
FORCEPROP 1 LAST VALUE 2.21K
J 2
(-345 3725);
DISPLAY 0.617021 (-345 3725);
PAINT SKYBLUE (-345 3725);
FORCEPROP 1 LAST TOLERANCE 1%
J 2
(-345 3675);
DISPLAY 0.617021 (-345 3675);
PAINT SKYBLUE (-345 3675);
FORCEPROP 1 LAST PACK_TYPE 0402
J 2
(-340 3475);
DISPLAY 0.617021 (-340 3475);
PAINT SKYBLUE (-340 3475);
FORCEPROP 1 LAST WATTAGE 1/16W
J 2
(-340 3625);
DISPLAY 0.617021 (-340 3625);
PAINT SKYBLUE (-340 3625);
FORCEPROP 1 LASTPIN (-300 3550) $PN 2
J 2
(-305 3560);
DISPLAY 0.617021 (-305 3560);
PAINT MONO (-305 3560);
FORCEPROP 1 LASTPIN (-300 3750) $PN 1
J 2
(-305 3712);
DISPLAY 0.617021 (-305 3712);
PAINT MONO (-305 3712);
FORCEPROP 1 LAST MATERIAL CHIP
J 2
(-340 3575);
DISPLAY 0.617021 (-340 3575);
PAINT SKYBLUE (-340 3575);
FORCEPROP 2 LAST SEC_TYPE 0402
J 2
(-350 3875);
PAINT MONO (-350 3875);
DISPLAY INVISIBLE (-350 3875);
FORCEPROP 2 LAST BOM_COST PROC_SIDEBAND
J 2
(-300 3650);
PAINT MONO (-300 3650);
DISPLAY INVISIBLE (-300 3650);
FORCEPROP 2 LAST CDS_LIB mstr_discrete
J 2
(-300 3650);
PAINT ORANGE (-300 3650);
DISPLAY INVISIBLE (-300 3650);
FORCEPROP 2 LAST SEC 1
J 2
(-350 3875);
DISPLAY 0.936170 (-350 3875);
PAINT MONO (-350 3875);
DISPLAY INVISIBLE (-350 3875);
FORCEPROP 2 LAST CDS_LOCATION R4U2
J 2
(-345 3775);
DISPLAY 0.617021 (-345 3775);
PAINT AQUA (-345 3775);
DISPLAY INVISIBLE (-345 3775);
FORCEPROP 1 LAST PATH I100
J 2
(-350 3825);
DISPLAY 0.978723 (-350 3825);
PAINT WHITE (-350 3825);
DISPLAY INVISIBLE (-350 3825);
FORCEPROP 2 LAST ROOM PROC_SIDEBAND
J 2
(-325 3425);
PAINT ORANGE (-325 3425);
DISPLAY INVISIBLE (-325 3425);
FORCEADD OFFPAGE..1
(-1650 3425);
FORCEPROP 2 LAST $XR23 88 
J 0
(-2261 3461);
DISPLAY 0.638298 (-2261 3461);
PAINT MONO (-2261 3461);
FORCEPROP 2 LAST $XR22 87 
J 0
(-2171 3461);
DISPLAY 0.638298 (-2171 3461);
PAINT MONO (-2171 3461);
FORCEPROP 2 LAST $XR21 86 
J 0
(-2081 3461);
DISPLAY 0.638298 (-2081 3461);
PAINT MONO (-2081 3461);
FORCEPROP 2 LAST $XR20 85 
J 0
(-1991 3461);
DISPLAY 0.638298 (-1991 3461);
PAINT MONO (-1991 3461);
FORCEPROP 2 LAST $XR19 84 
J 0
(-1901 3461);
DISPLAY 0.638298 (-1901 3461);
PAINT MONO (-1901 3461);
FORCEPROP 2 LAST $XR18 83 
J 0
(-2621 3389);
DISPLAY 0.638298 (-2621 3389);
PAINT MONO (-2621 3389);
FORCEPROP 2 LAST $XR17 82 
J 0
(-2531 3389);
DISPLAY 0.638298 (-2531 3389);
PAINT MONO (-2531 3389);
FORCEPROP 2 LAST $XR16 81 
J 0
(-2441 3389);
DISPLAY 0.638298 (-2441 3389);
PAINT MONO (-2441 3389);
FORCEPROP 2 LAST $XR15 80 
J 0
(-2351 3389);
DISPLAY 0.638298 (-2351 3389);
PAINT MONO (-2351 3389);
FORCEPROP 2 LAST $XR14 79 
J 0
(-2261 3389);
DISPLAY 0.638298 (-2261 3389);
PAINT MONO (-2261 3389);
FORCEPROP 2 LAST $XR13 78 
J 0
(-2171 3389);
DISPLAY 0.638298 (-2171 3389);
PAINT MONO (-2171 3389);
FORCEPROP 2 LAST $XR12 77 
J 0
(-2081 3389);
DISPLAY 0.638298 (-2081 3389);
PAINT MONO (-2081 3389);
FORCEPROP 2 LAST $XR11 54 
J 0
(-1991 3389);
DISPLAY 0.638298 (-1991 3389);
PAINT MONO (-1991 3389);
FORCEPROP 2 LAST $XR10 53 
J 0
(-1901 3389);
DISPLAY 0.638298 (-1901 3389);
PAINT MONO (-1901 3389);
FORCEPROP 2 LAST $XR9 52 
J 0
(-2711 3425);
DISPLAY 0.638298 (-2711 3425);
PAINT MONO (-2711 3425);
FORCEPROP 2 LAST $XR8 51 
J 0
(-2621 3425);
DISPLAY 0.638298 (-2621 3425);
PAINT MONO (-2621 3425);
FORCEPROP 2 LAST $XR7 50 
J 0
(-2531 3425);
DISPLAY 0.638298 (-2531 3425);
PAINT MONO (-2531 3425);
FORCEPROP 2 LAST $XR6 49 
J 0
(-2441 3425);
DISPLAY 0.638298 (-2441 3425);
PAINT MONO (-2441 3425);
FORCEPROP 2 LAST $XR5 48 
J 0
(-2351 3425);
DISPLAY 0.638298 (-2351 3425);
PAINT MONO (-2351 3425);
FORCEPROP 2 LAST $XR4 47 
J 0
(-2261 3425);
DISPLAY 0.638298 (-2261 3425);
PAINT MONO (-2261 3425);
FORCEPROP 2 LAST $XR3 46 
J 0
(-2171 3425);
DISPLAY 0.638298 (-2171 3425);
PAINT MONO (-2171 3425);
FORCEPROP 2 LAST $XR2 45 
J 0
(-2081 3425);
DISPLAY 0.638298 (-2081 3425);
PAINT MONO (-2081 3425);
FORCEPROP 2 LAST $XR1 44 
J 0
(-1991 3425);
DISPLAY 0.638298 (-1991 3425);
PAINT MONO (-1991 3425);
FORCEPROP 2 LAST $XR0 43 
J 0
(-1901 3425);
DISPLAY 0.638298 (-1901 3425);
PAINT MONO (-1901 3425);
FORCEPROP 2 LAST CDS_LIB mstr_standard
J 0
(-1650 3425);
PAINT MONO (-1650 3425);
DISPLAY INVISIBLE (-1650 3425);
FORCEPROP 2 LAST PATH I101
J 0
(-1900 3500);
DISPLAY 1.021277 (-1900 3500);
PAINT ORANGE (-1900 3500);
DISPLAY INVISIBLE (-1900 3500);
FORCEPROP 1 LAST OFFPAGE TRUE
J 0
(-1325 3300);
PAINT GREEN (-1325 3300);
DISPLAY INVISIBLE (-1325 3300);
FORCEPROP 1 LAST COMMENT_BODY TRUE
J 0
(-1525 3325);
DISPLAY 1.170213 (-1525 3325);
PAINT GREEN (-1525 3325);
DISPLAY INVISIBLE (-1525 3325);
FORCEADD FET_N_DUAL..5
(1400 3950);
FORCEPROP 1 LASTPIN (1400 3750) $PN 4
J 2
(1458 3750);
DISPLAY 0.617021 (1458 3750);
PAINT WHITE (1458 3750);
FORCEPROP 1 LAST LOCATION Q4U1
J 0
(1600 4050);
DISPLAY 0.617021 (1600 4050);
PAINT AQUA (1600 4050);
FORCEPROP 1 LASTPIN (1200 3850) $PN 5
J 2
(1203 3865);
DISPLAY 0.617021 (1203 3865);
PAINT WHITE (1203 3865);
FORCEPROP 1 LASTPIN (1400 4150) $PN 3
J 2
(1453 4115);
DISPLAY 0.617021 (1453 4115);
PAINT WHITE (1453 4115);
FORCEPROP 1 LAST PART_NUMBER E40049-001
J 0
(1600 4000);
DISPLAY 0.617021 (1600 4000);
PAINT BLUE (1600 4000);
FORCEPROP 1 LAST VALUE NTJD4001N
J 0
(1600 3950);
DISPLAY 0.617021 (1600 3950);
PAINT SKYBLUE (1600 3950);
FORCEPROP 1 LAST MATERIAL FET
J 0
(1600 3900);
DISPLAY 0.617021 (1600 3900);
PAINT SKYBLUE (1600 3900);
FORCEPROP 1 LAST PACK_TYPE SMLF
J 0
(1600 3800);
PAINT SKYBLUE (1600 3800);
DISPLAY INVISIBLE (1600 3800);
FORCEPROP 2 LAST SEC_TYPE SMLF
J 0
(1000 4200);
DISPLAY 1.021277 (1000 4200);
PAINT ORANGE (1000 4200);
DISPLAY INVISIBLE (1000 4200);
FORCEPROP 2 LAST CDS_LIB mstr_discrete
J 0
(1400 3950);
PAINT ORANGE (1400 3950);
DISPLAY INVISIBLE (1400 3950);
FORCEPROP 2 LAST BOM_COST PROC_SIDEBAND
J 0
(1400 3950);
PAINT MONO (1400 3950);
DISPLAY INVISIBLE (1400 3950);
FORCEPROP 2 LAST SEC 2
J 0
(1000 4200);
DISPLAY 0.680851 (1000 4200);
PAINT MONO (1000 4200);
DISPLAY INVISIBLE (1000 4200);
FORCEPROP 2 LAST CDS_LOCATION Q4U1
J 0
(1600 3950);
DISPLAY 0.617021 (1600 3950);
PAINT AQUA (1600 3950);
DISPLAY INVISIBLE (1600 3950);
FORCEPROP 1 LAST PATH I102
J 0
(1600 4000);
DISPLAY 0.978723 (1600 4000);
PAINT BLUE (1600 4000);
DISPLAY INVISIBLE (1600 4000);
FORCEPROP 2 LAST ROOM PROC_SIDEBAND
J 0
(1600 4050);
PAINT ORANGE (1600 4050);
DISPLAY INVISIBLE (1600 4050);
FORCEADD PVPP_ABC..1
(175 4300);
FORCEPROP 3 LASTPIN (175 4250) SIG_NAME PVPP_ABC\g
J 0
(185 4260);
DISPLAY 0.659574 (185 4260);
PAINT MONO (185 4260);
DISPLAY INVISIBLE (185 4260);
FORCEPROP 1 LAST VOLTAGE 2.5V
J 0
(130 4257);
DISPLAY 0.340426 (130 4257);
PAINT SKYBLUE (130 4257);
DISPLAY INVISIBLE (130 4257);
FORCEPROP 2 LAST BOM_COST PVPP_KLM_VR
J 0
(250 4400);
PAINT MONO (250 4400);
DISPLAY INVISIBLE (250 4400);
FORCEPROP 2 LAST CDS_LIB mstr_symbols
J 0
(175 4300);
PAINT ORANGE (175 4300);
DISPLAY INVISIBLE (175 4300);
FORCEPROP 1 LAST PATH I103
J 0
(225 4325);
DISPLAY 0.872340 (225 4325);
PAINT AQUA (225 4325);
DISPLAY INVISIBLE (225 4325);
FORCEPROP 2 LAST ROOM PVPP_KLM_VR
J 0
(425 4400);
PAINT ORANGE (425 4400);
DISPLAY INVISIBLE (425 4400);
FORCEPROP 1 LAST BODY_TYPE PLUMBING
J 0
(130 4257);
DISPLAY 0.340426 (130 4257);
PAINT GREEN (130 4257);
DISPLAY INVISIBLE (130 4257);
FORCEPROP 1 LAST HDL_POWER PVPP_ABC
J 1
(175 4350);
DISPLAY 0.872340 (175 4350);
PAINT GREEN (175 4350);
DISPLAY INVISIBLE (175 4350);
FORCEADD RES..2
(750 3575);
FORCEPROP 1 LAST TOLERANCE 5%
J 0
(795 3600);
DISPLAY 0.617021 (795 3600);
PAINT SKYBLUE (795 3600);
FORCEPROP 1 LAST MATERIAL CHIP
J 0
(790 3500);
DISPLAY 0.617021 (790 3500);
PAINT SKYBLUE (790 3500);
FORCEPROP 1 LAST WATTAGE 1/16W
J 0
(790 3550);
DISPLAY 0.617021 (790 3550);
PAINT SKYBLUE (790 3550);
FORCEPROP 1 LASTPIN (750 3475) $PN 2
J 0
(755 3485);
DISPLAY 0.617021 (755 3485);
PAINT ORANGE (755 3485);
FORCEPROP 1 LAST PART_NUMBER G21497-023
J 0
(790 3450);
DISPLAY 0.617021 (790 3450);
PAINT BLUE (790 3450);
FORCEPROP 1 LAST PACK_TYPE 0402
J 0
(790 3400);
DISPLAY 0.617021 (790 3400);
PAINT SKYBLUE (790 3400);
FORCEPROP 1 LASTPIN (750 3675) $PN 1
J 0
(755 3637);
DISPLAY 0.617021 (755 3637);
PAINT ORANGE (755 3637);
FORCEPROP 1 LAST VALUE 33.0K
J 0
(795 3650);
DISPLAY 0.617021 (795 3650);
PAINT SKYBLUE (795 3650);
FORCEPROP 1 LAST LOCATION R4U4
J 0
(795 3700);
DISPLAY 0.617021 (795 3700);
PAINT AQUA (795 3700);
FORCEPROP 2 LAST CDS_LIB mstr_discrete
J 0
(750 3575);
PAINT ORANGE (750 3575);
DISPLAY INVISIBLE (750 3575);
FORCEPROP 2 LAST SEC_TYPE 0402
J 0
(800 3800);
DISPLAY 1.021277 (800 3800);
PAINT ORANGE (800 3800);
DISPLAY INVISIBLE (800 3800);
FORCEPROP 2 LAST SEC 1
J 0
(800 3800);
DISPLAY 0.680851 (800 3800);
PAINT MONO (800 3800);
DISPLAY INVISIBLE (800 3800);
FORCEPROP 2 LAST CDS_LOCATION R4U4
J 0
(795 3700);
DISPLAY 0.617021 (795 3700);
PAINT AQUA (795 3700);
DISPLAY INVISIBLE (795 3700);
FORCEPROP 1 LAST PATH I104
J 0
(800 3750);
DISPLAY 0.978723 (800 3750);
PAINT WHITE (800 3750);
DISPLAY INVISIBLE (800 3750);
FORCEADD GND..1
(750 3225);
FORCEPROP 3 LASTPIN (750 3275) SIG_NAME GND\g
J 0
(760 3285);
DISPLAY 0.659574 (760 3285);
PAINT MONO (760 3285);
DISPLAY INVISIBLE (760 3285);
FORCEPROP 1 LAST VOLTAGE 0
J 0
(750 3225);
PAINT SKYBLUE (750 3225);
DISPLAY INVISIBLE (750 3225);
FORCEPROP 2 LAST CDS_LIB mstr_symbols
J 0
(750 3225);
PAINT ORANGE (750 3225);
DISPLAY INVISIBLE (750 3225);
FORCEPROP 1 LAST SIZE 1B
J 0
(825 3175);
DISPLAY 1.170213 (825 3175);
PAINT GREEN (825 3175);
DISPLAY INVISIBLE (825 3175);
FORCEPROP 1 LAST PATH I105
J 0
(825 3225);
DISPLAY 0.872340 (825 3225);
PAINT AQUA (825 3225);
DISPLAY INVISIBLE (825 3225);
FORCEPROP 1 LAST BODY_TYPE PLUMBING
J 0
(705 3182);
DISPLAY 0.340426 (705 3182);
PAINT GREEN (705 3182);
DISPLAY INVISIBLE (705 3182);
FORCEPROP 1 LAST HDL_POWER GND
J 0
(750 3375);
DISPLAY 1.170213 (750 3375);
PAINT GREEN (750 3375);
DISPLAY INVISIBLE (750 3375);
FORCEADD OFFPAGE..5
R 2
(-675 2300);
FORCEPROP 2 LAST $XR2 152 
J 0
(-306 2300);
DISPLAY 0.638298 (-306 2300);
PAINT MONO (-306 2300);
FORCEPROP 2 LAST $XR1 21 
J 0
(-396 2300);
DISPLAY 0.638298 (-396 2300);
PAINT MONO (-396 2300);
FORCEPROP 2 LAST $XR0 95 
J 0
(-486 2300);
DISPLAY 0.638298 (-486 2300);
PAINT MONO (-486 2300);
FORCEPROP 2 LAST CDS_LIB mstr_standard
J 1
(-675 2300);
PAINT ORANGE (-675 2300);
DISPLAY INVISIBLE (-675 2300);
FORCEPROP 2 LAST ROOM PROC_SIDEBAND
J 2
(-365 2330);
DISPLAY 0.978723 (-365 2330);
PAINT ORANGE (-365 2330);
DISPLAY INVISIBLE (-365 2330);
FORCEPROP 2 LAST PATH I39
J 0
(-380 2350);
DISPLAY 1.021277 (-380 2350);
PAINT ORANGE (-380 2350);
DISPLAY INVISIBLE (-380 2350);
FORCEPROP 1 LAST OFFPAGE TRUE
J 2
(-1000 2175);
PAINT GREEN (-1000 2175);
DISPLAY INVISIBLE (-1000 2175);
FORCEPROP 1 LAST COMMENT_BODY TRUE
J 2
(-775 2225);
DISPLAY 0.978723 (-775 2225);
PAINT GREEN (-775 2225);
DISPLAY INVISIBLE (-775 2225);
FORCEADD GND..1
(-1425 1750);
FORCEPROP 3 LASTPIN (-1425 1800) SIG_NAME GND\g
J 0
(-1415 1810);
DISPLAY 0.659574 (-1415 1810);
PAINT MONO (-1415 1810);
DISPLAY INVISIBLE (-1415 1810);
FORCEPROP 1 LAST VOLTAGE 0
J 0
(-1425 1750);
PAINT SKYBLUE (-1425 1750);
DISPLAY INVISIBLE (-1425 1750);
FORCEPROP 1 LAST SIZE 1B
J 0
(-1350 1700);
DISPLAY 1.170213 (-1350 1700);
PAINT GREEN (-1350 1700);
DISPLAY INVISIBLE (-1350 1700);
FORCEPROP 2 LAST CDS_LIB mstr_symbols
J 0
(-1425 1750);
PAINT ORANGE (-1425 1750);
DISPLAY INVISIBLE (-1425 1750);
FORCEPROP 1 LAST PATH I47
J 0
(-1350 1750);
DISPLAY 0.872340 (-1350 1750);
PAINT AQUA (-1350 1750);
DISPLAY INVISIBLE (-1350 1750);
FORCEPROP 2 LAST ROOM PROCHOT_MEMHOT_ISO
J 0
(-1800 1825);
PAINT ORANGE (-1800 1825);
DISPLAY INVISIBLE (-1800 1825);
FORCEPROP 1 LAST BODY_TYPE PLUMBING
J 0
(-1470 1707);
DISPLAY 0.340426 (-1470 1707);
PAINT GREEN (-1470 1707);
DISPLAY INVISIBLE (-1470 1707);
FORCEPROP 1 LAST HDL_POWER GND
J 0
(-1425 1900);
DISPLAY 1.170213 (-1425 1900);
PAINT GREEN (-1425 1900);
DISPLAY INVISIBLE (-1425 1900);
FORCEADD FET_N_DUAL..5
(-2150 1925);
FORCEPROP 1 LAST LOCATION Q3U1
J 0
(-2025 1750);
DISPLAY 0.617021 (-2025 1750);
PAINT AQUA (-2025 1750);
FORCEPROP 1 LAST PART_NUMBER E40049-001
J 0
(-2025 1600);
DISPLAY 0.617021 (-2025 1600);
PAINT BLUE (-2025 1600);
FORCEPROP 1 LAST MATERIAL FET
J 0
(-2025 1650);
DISPLAY 0.617021 (-2025 1650);
PAINT SKYBLUE (-2025 1650);
FORCEPROP 1 LASTPIN (-2150 1725) $PN 1
J 2
(-2092 1725);
DISPLAY 0.617021 (-2092 1725);
PAINT MONO (-2092 1725);
FORCEPROP 1 LASTPIN (-2350 1825) $PN 2
J 2
(-2347 1840);
DISPLAY 0.617021 (-2347 1840);
PAINT MONO (-2347 1840);
FORCEPROP 1 LASTPIN (-2150 2125) $PN 6
J 2
(-2097 2090);
DISPLAY 0.617021 (-2097 2090);
PAINT MONO (-2097 2090);
FORCEPROP 1 LAST VALUE NTJD4001N
J 0
(-2025 1700);
DISPLAY 0.617021 (-2025 1700);
PAINT SKYBLUE (-2025 1700);
FORCEPROP 1 LAST PACK_TYPE SMLF
J 0
(-1950 1775);
PAINT SKYBLUE (-1950 1775);
DISPLAY INVISIBLE (-1950 1775);
FORCEPROP 2 LAST CDS_LIB mstr_discrete
J 0
(-2150 1925);
PAINT ORANGE (-2150 1925);
DISPLAY INVISIBLE (-2150 1925);
FORCEPROP 2 LAST SEC_TYPE SMLF
J 0
(-1950 2025);
DISPLAY 1.404255 (-1950 2025);
PAINT ORANGE (-1950 2025);
DISPLAY INVISIBLE (-1950 2025);
FORCEPROP 2 LAST SEC 1
J 0
(-1950 2025);
DISPLAY 0.936170 (-1950 2025);
PAINT MONO (-1950 2025);
DISPLAY INVISIBLE (-1950 2025);
FORCEPROP 2 LAST CDS_LOCATION Q3U1
J 0
(-2025 1750);
DISPLAY 0.617021 (-2025 1750);
PAINT AQUA (-2025 1750);
DISPLAY INVISIBLE (-2025 1750);
FORCEPROP 1 LAST PATH I49
J 0
(-1950 1975);
DISPLAY 0.978723 (-1950 1975);
PAINT BLUE (-1950 1975);
DISPLAY INVISIBLE (-1950 1975);
FORCEPROP 2 LAST ROOM PROC_SIDEBAND
J 0
(-2150 1965);
DISPLAY 0.787234 (-2150 1965);
PAINT SKYBLUE (-2150 1965);
DISPLAY INVISIBLE (-2150 1965);
FORCEADD P3V3..1
(-2150 2575);
FORCEPROP 3 LASTPIN (-2150 2525) SIG_NAME P3V3\g
J 0
(-2140 2535);
DISPLAY 0.659574 (-2140 2535);
PAINT MONO (-2140 2535);
DISPLAY INVISIBLE (-2140 2535);
FORCEPROP 1 LAST VOLTAGE +3.3
J 0
(-2150 2575);
PAINT SKYBLUE (-2150 2575);
DISPLAY INVISIBLE (-2150 2575);
FORCEPROP 2 LAST CDS_LIB mstr_symbols
J 0
(-2150 2575);
PAINT ORANGE (-2150 2575);
DISPLAY INVISIBLE (-2150 2575);
FORCEPROP 1 LAST SIZE 1B
J 0
(-2105 2597);
DISPLAY 0.553191 (-2105 2597);
PAINT GREEN (-2105 2597);
DISPLAY INVISIBLE (-2105 2597);
FORCEPROP 1 LAST PATH I50
J 0
(-2105 2577);
DISPLAY 0.340426 (-2105 2577);
PAINT GREEN (-2105 2577);
DISPLAY INVISIBLE (-2105 2577);
FORCEPROP 2 LAST ROOM PROC_SIDEBAND
J 0
(-2300 2675);
PAINT PEACH (-2300 2675);
DISPLAY INVISIBLE (-2300 2675);
FORCEPROP 1 LAST BODY_TYPE PLUMBING
J 0
(-2195 2532);
DISPLAY 0.468085 (-2195 2532);
PAINT GREEN (-2195 2532);
DISPLAY INVISIBLE (-2195 2532);
FORCEPROP 1 LAST HDL_POWER P3V3
J 0
(-2475 2450);
DISPLAY 1.170213 (-2475 2450);
PAINT GREEN (-2475 2450);
DISPLAY INVISIBLE (-2475 2450);
FORCEADD RES..2
R 2
(-2150 2375);
FORCEPROP 1 LAST LOCATION R7G7
J 2
(-2195 2450);
DISPLAY 0.617021 (-2195 2450);
PAINT AQUA (-2195 2450);
FORCEPROP 1 LAST VALUE 4.75K
J 2
(-2195 2400);
DISPLAY 0.617021 (-2195 2400);
PAINT SKYBLUE (-2195 2400);
FORCEPROP 1 LAST TOLERANCE 1%
J 2
(-2195 2350);
DISPLAY 0.617021 (-2195 2350);
PAINT SKYBLUE (-2195 2350);
FORCEPROP 1 LAST PACK_TYPE 0402
J 2
(-2190 2200);
DISPLAY 0.617021 (-2190 2200);
PAINT SKYBLUE (-2190 2200);
FORCEPROP 1 LAST MATERIAL CHIP
J 2
(-2190 2250);
DISPLAY 0.617021 (-2190 2250);
PAINT SKYBLUE (-2190 2250);
FORCEPROP 1 LAST WATTAGE 1/16W
J 2
(-2190 2300);
DISPLAY 0.617021 (-2190 2300);
PAINT SKYBLUE (-2190 2300);
FORCEPROP 1 LASTPIN (-2150 2275) $PN 2
J 2
(-2155 2285);
DISPLAY 0.617021 (-2155 2285);
PAINT MONO (-2155 2285);
FORCEPROP 1 LASTPIN (-2150 2475) $PN 1
J 2
(-2155 2437);
DISPLAY 0.617021 (-2155 2437);
PAINT MONO (-2155 2437);
FORCEPROP 1 LAST PART_NUMBER G21796-072
R 1
J 0
(-2090 2250);
DISPLAY 0.617021 (-2090 2250);
PAINT BLUE (-2090 2250);
FORCEPROP 2 LAST CDS_LIB mstr_discrete
J 2
(-2150 2375);
DISPLAY 1.361702 (-2150 2375);
PAINT ORANGE (-2150 2375);
DISPLAY INVISIBLE (-2150 2375);
FORCEPROP 2 LAST BOM_COST PROC_SIDEBAND
J 0
(-2150 2375);
PAINT MONO (-2150 2375);
DISPLAY INVISIBLE (-2150 2375);
FORCEPROP 2 LAST CDS_SEC 1
J 1
(-2200 2600);
DISPLAY 1.404255 (-2200 2600);
PAINT ORANGE (-2200 2600);
DISPLAY INVISIBLE (-2200 2600);
FORCEPROP 2 LAST $SEC 1
J 1
(-2200 2600);
DISPLAY 0.936170 (-2200 2600);
PAINT MONO (-2200 2600);
DISPLAY INVISIBLE (-2200 2600);
FORCEPROP 2 LAST CDS_LOCATION R7G7
J 2
(-2195 2450);
DISPLAY 0.617021 (-2195 2450);
PAINT AQUA (-2195 2450);
DISPLAY INVISIBLE (-2195 2450);
FORCEPROP 1 LAST PATH I51
J 2
(-2200 2550);
DISPLAY 0.978723 (-2200 2550);
PAINT WHITE (-2200 2550);
DISPLAY INVISIBLE (-2200 2550);
FORCEPROP 2 LAST ROOM PROC_SIDEBAND
J 2
(-2200 2550);
PAINT PEACH (-2200 2550);
DISPLAY INVISIBLE (-2200 2550);
FORCEADD GND..1
(-2150 1650);
FORCEPROP 3 LASTPIN (-2150 1700) SIG_NAME GND\g
J 0
(-2140 1710);
DISPLAY 0.659574 (-2140 1710);
PAINT MONO (-2140 1710);
DISPLAY INVISIBLE (-2140 1710);
FORCEPROP 1 LAST VOLTAGE 0
J 0
(-2150 1650);
PAINT SKYBLUE (-2150 1650);
DISPLAY INVISIBLE (-2150 1650);
FORCEPROP 1 LAST SIZE 1B
J 0
(-2075 1600);
DISPLAY 1.170213 (-2075 1600);
PAINT GREEN (-2075 1600);
DISPLAY INVISIBLE (-2075 1600);
FORCEPROP 2 LAST CDS_LIB mstr_symbols
J 0
(-2150 1650);
PAINT ORANGE (-2150 1650);
DISPLAY INVISIBLE (-2150 1650);
FORCEPROP 1 LAST PATH I56
J 0
(-2075 1650);
DISPLAY 0.872340 (-2075 1650);
PAINT AQUA (-2075 1650);
DISPLAY INVISIBLE (-2075 1650);
FORCEPROP 2 LAST ROOM PROCHOT_MEMHOT_ISO
J 0
(-2525 1725);
PAINT ORANGE (-2525 1725);
DISPLAY INVISIBLE (-2525 1725);
FORCEPROP 1 LAST BODY_TYPE PLUMBING
J 0
(-2195 1607);
DISPLAY 0.340426 (-2195 1607);
PAINT GREEN (-2195 1607);
DISPLAY INVISIBLE (-2195 1607);
FORCEPROP 1 LAST HDL_POWER GND
J 0
(-2150 1800);
DISPLAY 1.170213 (-2150 1800);
PAINT GREEN (-2150 1800);
DISPLAY INVISIBLE (-2150 1800);
FORCEADD OFFPAGE..1
(-3325 1825);
FORCEPROP 2 LAST $XR2 145 
J 0
(-3577 1789);
DISPLAY 0.638298 (-3577 1789);
PAINT MONO (-3577 1789);
FORCEPROP 2 LAST $XR1 119 
J 0
(-3697 1825);
DISPLAY 0.638298 (-3697 1825);
PAINT MONO (-3697 1825);
FORCEPROP 2 LAST $XR0 215 
J 0
(-3577 1825);
DISPLAY 0.638298 (-3577 1825);
PAINT MONO (-3577 1825);
FORCEPROP 2 LAST CDS_LIB mstr_standard
J 0
(-3325 1825);
PAINT ORANGE (-3325 1825);
DISPLAY INVISIBLE (-3325 1825);
FORCEPROP 2 LAST ROOM PROCHOT_MEMHOT_ISO
J 0
(-3575 1875);
DISPLAY 0.978723 (-3575 1875);
PAINT ORANGE (-3575 1875);
DISPLAY INVISIBLE (-3575 1875);
FORCEPROP 2 LAST PATH I59
J 0
(-3575 1875);
DISPLAY 1.021277 (-3575 1875);
PAINT ORANGE (-3575 1875);
DISPLAY INVISIBLE (-3575 1875);
FORCEPROP 1 LAST OFFPAGE TRUE
J 0
(-3000 1700);
PAINT GREEN (-3000 1700);
DISPLAY INVISIBLE (-3000 1700);
FORCEPROP 1 LAST COMMENT_BODY TRUE
J 0
(-3200 1725);
DISPLAY 0.978723 (-3200 1725);
PAINT PEACH (-3200 1725);
DISPLAY INVISIBLE (-3200 1725);
FORCEADD FET_N_DUAL..5
(-2150 825);
FORCEPROP 1 LAST LOCATION Q7E1
J 0
(-2025 650);
DISPLAY 0.617021 (-2025 650);
PAINT AQUA (-2025 650);
FORCEPROP 1 LAST PART_NUMBER E40049-001
J 0
(-2025 500);
DISPLAY 0.617021 (-2025 500);
PAINT BLUE (-2025 500);
FORCEPROP 1 LAST VALUE NTJD4001N
J 0
(-2025 600);
DISPLAY 0.617021 (-2025 600);
PAINT SKYBLUE (-2025 600);
FORCEPROP 1 LAST MATERIAL FET
J 0
(-2025 550);
DISPLAY 0.617021 (-2025 550);
PAINT SKYBLUE (-2025 550);
FORCEPROP 1 LASTPIN (-2150 625) $PN 1
J 2
(-2092 625);
DISPLAY 0.617021 (-2092 625);
PAINT MONO (-2092 625);
FORCEPROP 1 LASTPIN (-2350 725) $PN 2
J 2
(-2347 740);
DISPLAY 0.617021 (-2347 740);
PAINT MONO (-2347 740);
FORCEPROP 1 LASTPIN (-2150 1025) $PN 6
J 2
(-2097 990);
DISPLAY 0.617021 (-2097 990);
PAINT MONO (-2097 990);
FORCEPROP 1 LAST PACK_TYPE SMLF
J 0
(-1950 675);
PAINT SKYBLUE (-1950 675);
DISPLAY INVISIBLE (-1950 675);
FORCEPROP 2 LAST CDS_LIB mstr_discrete
J 0
(-2150 825);
PAINT ORANGE (-2150 825);
DISPLAY INVISIBLE (-2150 825);
FORCEPROP 2 LAST SEC_TYPE SMLF
J 0
(-1950 925);
DISPLAY 1.404255 (-1950 925);
PAINT ORANGE (-1950 925);
DISPLAY INVISIBLE (-1950 925);
FORCEPROP 2 LAST SEC 1
J 0
(-1950 925);
DISPLAY 0.936170 (-1950 925);
PAINT MONO (-1950 925);
DISPLAY INVISIBLE (-1950 925);
FORCEPROP 2 LAST CDS_LOCATION Q7E1
J 0
(-2025 650);
DISPLAY 0.617021 (-2025 650);
PAINT AQUA (-2025 650);
DISPLAY INVISIBLE (-2025 650);
FORCEPROP 1 LAST PATH I60
J 0
(-1950 875);
DISPLAY 0.978723 (-1950 875);
PAINT BLUE (-1950 875);
DISPLAY INVISIBLE (-1950 875);
FORCEPROP 2 LAST ROOM PROC_SIDEBAND
J 0
(-2150 865);
DISPLAY 0.787234 (-2150 865);
PAINT SKYBLUE (-2150 865);
DISPLAY INVISIBLE (-2150 865);
FORCEADD OFFPAGE..5
R 2
(-675 1200);
FORCEPROP 2 LAST $XR2 152 
J 0
(-306 1200);
DISPLAY 0.638298 (-306 1200);
PAINT MONO (-306 1200);
FORCEPROP 2 LAST $XR1 21 
J 0
(-396 1200);
DISPLAY 0.638298 (-396 1200);
PAINT MONO (-396 1200);
FORCEPROP 2 LAST $XR0 95 
J 0
(-486 1200);
DISPLAY 0.638298 (-486 1200);
PAINT MONO (-486 1200);
FORCEPROP 2 LAST ROOM PROCHOT_MEMHOT_ISO
J 2
(-365 1230);
DISPLAY 0.978723 (-365 1230);
PAINT ORANGE (-365 1230);
DISPLAY INVISIBLE (-365 1230);
FORCEPROP 2 LAST CDS_LIB mstr_standard
J 1
(-675 1200);
PAINT ORANGE (-675 1200);
DISPLAY INVISIBLE (-675 1200);
FORCEPROP 2 LAST PATH I61
J 0
(-380 1250);
DISPLAY 1.021277 (-380 1250);
PAINT ORANGE (-380 1250);
DISPLAY INVISIBLE (-380 1250);
FORCEPROP 1 LAST OFFPAGE TRUE
J 2
(-1000 1075);
PAINT GREEN (-1000 1075);
DISPLAY INVISIBLE (-1000 1075);
FORCEPROP 1 LAST COMMENT_BODY TRUE
J 2
(-775 1125);
DISPLAY 0.978723 (-775 1125);
PAINT GREEN (-775 1125);
DISPLAY INVISIBLE (-775 1125);
FORCEADD GND..1
(-1425 650);
FORCEPROP 3 LASTPIN (-1425 700) SIG_NAME GND\g
J 0
(-1415 710);
DISPLAY 0.659574 (-1415 710);
PAINT MONO (-1415 710);
DISPLAY INVISIBLE (-1415 710);
FORCEPROP 1 LAST VOLTAGE 0
J 0
(-1425 650);
PAINT SKYBLUE (-1425 650);
DISPLAY INVISIBLE (-1425 650);
FORCEPROP 1 LAST SIZE 1B
J 0
(-1350 600);
DISPLAY 1.170213 (-1350 600);
PAINT GREEN (-1350 600);
DISPLAY INVISIBLE (-1350 600);
FORCEPROP 2 LAST CDS_LIB mstr_symbols
J 0
(-1425 650);
PAINT ORANGE (-1425 650);
DISPLAY INVISIBLE (-1425 650);
FORCEPROP 1 LAST PATH I63
J 0
(-1350 650);
DISPLAY 0.872340 (-1350 650);
PAINT AQUA (-1350 650);
DISPLAY INVISIBLE (-1350 650);
FORCEPROP 2 LAST ROOM PROCHOT_MEMHOT_ISO
J 0
(-1800 725);
PAINT ORANGE (-1800 725);
DISPLAY INVISIBLE (-1800 725);
FORCEPROP 1 LAST BODY_TYPE PLUMBING
J 0
(-1470 607);
DISPLAY 0.340426 (-1470 607);
PAINT GREEN (-1470 607);
DISPLAY INVISIBLE (-1470 607);
FORCEPROP 1 LAST HDL_POWER GND
J 0
(-1425 800);
DISPLAY 1.170213 (-1425 800);
PAINT GREEN (-1425 800);
DISPLAY INVISIBLE (-1425 800);
FORCEADD FET_N_DUAL..5
(-1425 950);
FORCEPROP 1 LAST LOCATION Q7E1
J 0
(-1275 800);
DISPLAY 0.617021 (-1275 800);
PAINT AQUA (-1275 800);
FORCEPROP 1 LAST PART_NUMBER E40049-001
J 0
(-1275 650);
DISPLAY 0.617021 (-1275 650);
PAINT BLUE (-1275 650);
FORCEPROP 1 LAST VALUE NTJD4001N
J 0
(-1275 750);
DISPLAY 0.617021 (-1275 750);
PAINT SKYBLUE (-1275 750);
FORCEPROP 1 LAST MATERIAL FET
J 0
(-1275 700);
DISPLAY 0.617021 (-1275 700);
PAINT SKYBLUE (-1275 700);
FORCEPROP 1 LASTPIN (-1425 750) $PN 4
J 2
(-1367 750);
DISPLAY 0.617021 (-1367 750);
PAINT MONO (-1367 750);
FORCEPROP 1 LASTPIN (-1625 850) $PN 5
J 2
(-1622 865);
DISPLAY 0.617021 (-1622 865);
PAINT MONO (-1622 865);
FORCEPROP 1 LASTPIN (-1425 1150) $PN 3
J 2
(-1372 1115);
DISPLAY 0.617021 (-1372 1115);
PAINT MONO (-1372 1115);
FORCEPROP 1 LAST PACK_TYPE SMLF
J 0
(-1225 800);
PAINT SKYBLUE (-1225 800);
DISPLAY INVISIBLE (-1225 800);
FORCEPROP 2 LAST CDS_LIB mstr_discrete
J 0
(-1425 950);
PAINT ORANGE (-1425 950);
DISPLAY INVISIBLE (-1425 950);
FORCEPROP 2 LAST SEC_TYPE SMLF
J 0
(-1225 1050);
DISPLAY 1.404255 (-1225 1050);
PAINT ORANGE (-1225 1050);
DISPLAY INVISIBLE (-1225 1050);
FORCEPROP 2 LAST SEC 2
J 0
(-1225 1050);
DISPLAY 0.936170 (-1225 1050);
PAINT MONO (-1225 1050);
DISPLAY INVISIBLE (-1225 1050);
FORCEPROP 2 LAST CDS_LOCATION Q7E1
J 0
(-1275 800);
DISPLAY 0.617021 (-1275 800);
PAINT AQUA (-1275 800);
DISPLAY INVISIBLE (-1275 800);
FORCEPROP 1 LAST PATH I64
J 0
(-1225 1000);
DISPLAY 0.978723 (-1225 1000);
PAINT BLUE (-1225 1000);
DISPLAY INVISIBLE (-1225 1000);
FORCEPROP 2 LAST ROOM PROC_SIDEBAND
J 0
(-1425 990);
DISPLAY 0.787234 (-1425 990);
PAINT SKYBLUE (-1425 990);
DISPLAY INVISIBLE (-1425 990);
FORCEADD P3V3..1
(-2150 1475);
FORCEPROP 3 LASTPIN (-2150 1425) SIG_NAME P3V3\g
J 0
(-2140 1435);
DISPLAY 0.659574 (-2140 1435);
PAINT MONO (-2140 1435);
DISPLAY INVISIBLE (-2140 1435);
FORCEPROP 1 LAST VOLTAGE +3.3
J 0
(-2150 1475);
PAINT SKYBLUE (-2150 1475);
DISPLAY INVISIBLE (-2150 1475);
FORCEPROP 1 LAST SIZE 1B
J 0
(-2105 1497);
DISPLAY 0.553191 (-2105 1497);
PAINT GREEN (-2105 1497);
DISPLAY INVISIBLE (-2105 1497);
FORCEPROP 2 LAST CDS_LIB mstr_symbols
J 0
(-2150 1475);
PAINT ORANGE (-2150 1475);
DISPLAY INVISIBLE (-2150 1475);
FORCEPROP 1 LAST PATH I65
J 0
(-2105 1477);
DISPLAY 0.340426 (-2105 1477);
PAINT GREEN (-2105 1477);
DISPLAY INVISIBLE (-2105 1477);
FORCEPROP 2 LAST ROOM PROCHOT_MEMHOT_ISO
J 0
(-2300 1575);
PAINT PEACH (-2300 1575);
DISPLAY INVISIBLE (-2300 1575);
FORCEPROP 1 LAST BODY_TYPE PLUMBING
J 0
(-2195 1432);
DISPLAY 0.468085 (-2195 1432);
PAINT GREEN (-2195 1432);
DISPLAY INVISIBLE (-2195 1432);
FORCEPROP 1 LAST HDL_POWER P3V3
J 0
(-2475 1350);
DISPLAY 1.170213 (-2475 1350);
PAINT GREEN (-2475 1350);
DISPLAY INVISIBLE (-2475 1350);
FORCEADD RES..2
R 2
(-2150 1275);
FORCEPROP 1 LAST LOCATION R3R4
J 2
(-2195 1350);
DISPLAY 0.617021 (-2195 1350);
PAINT AQUA (-2195 1350);
FORCEPROP 1 LAST PART_NUMBER G21796-072
R 1
J 0
(-2090 1150);
DISPLAY 0.617021 (-2090 1150);
PAINT BLUE (-2090 1150);
FORCEPROP 1 LAST VALUE 4.75K
J 2
(-2195 1300);
DISPLAY 0.617021 (-2195 1300);
PAINT SKYBLUE (-2195 1300);
FORCEPROP 1 LAST TOLERANCE 1%
J 2
(-2195 1250);
DISPLAY 0.617021 (-2195 1250);
PAINT SKYBLUE (-2195 1250);
FORCEPROP 1 LAST PACK_TYPE 0402
J 2
(-2190 1100);
DISPLAY 0.617021 (-2190 1100);
PAINT SKYBLUE (-2190 1100);
FORCEPROP 1 LAST MATERIAL CHIP
J 2
(-2190 1150);
DISPLAY 0.617021 (-2190 1150);
PAINT SKYBLUE (-2190 1150);
FORCEPROP 1 LAST WATTAGE 1/16W
J 2
(-2190 1200);
DISPLAY 0.617021 (-2190 1200);
PAINT SKYBLUE (-2190 1200);
FORCEPROP 1 LASTPIN (-2150 1175) $PN 2
J 2
(-2155 1185);
DISPLAY 0.617021 (-2155 1185);
PAINT MONO (-2155 1185);
FORCEPROP 1 LASTPIN (-2150 1375) $PN 1
J 2
(-2155 1337);
DISPLAY 0.617021 (-2155 1337);
PAINT MONO (-2155 1337);
FORCEPROP 2 LAST CDS_LIB mstr_discrete
J 2
(-2150 1275);
DISPLAY 1.361702 (-2150 1275);
PAINT ORANGE (-2150 1275);
DISPLAY INVISIBLE (-2150 1275);
FORCEPROP 2 LAST BOM_COST PROC_SIDEBAND
J 0
(-2150 1275);
PAINT MONO (-2150 1275);
DISPLAY INVISIBLE (-2150 1275);
FORCEPROP 2 LAST CDS_SEC 1
J 1
(-2200 1500);
DISPLAY 1.404255 (-2200 1500);
PAINT ORANGE (-2200 1500);
DISPLAY INVISIBLE (-2200 1500);
FORCEPROP 2 LAST $SEC 1
J 1
(-2200 1500);
DISPLAY 0.936170 (-2200 1500);
PAINT MONO (-2200 1500);
DISPLAY INVISIBLE (-2200 1500);
FORCEPROP 2 LAST CDS_LOCATION R3R4
J 2
(-2195 1350);
DISPLAY 0.617021 (-2195 1350);
PAINT AQUA (-2195 1350);
DISPLAY INVISIBLE (-2195 1350);
FORCEPROP 1 LAST PATH I66
J 2
(-2200 1450);
DISPLAY 0.978723 (-2200 1450);
PAINT WHITE (-2200 1450);
DISPLAY INVISIBLE (-2200 1450);
FORCEPROP 2 LAST ROOM PROC_SIDEBAND
J 2
(-2200 1450);
PAINT PEACH (-2200 1450);
DISPLAY INVISIBLE (-2200 1450);
FORCEADD GND..1
(-2150 550);
FORCEPROP 3 LASTPIN (-2150 600) SIG_NAME GND\g
J 0
(-2140 610);
DISPLAY 0.659574 (-2140 610);
PAINT MONO (-2140 610);
DISPLAY INVISIBLE (-2140 610);
FORCEPROP 1 LAST VOLTAGE 0
J 0
(-2150 550);
PAINT SKYBLUE (-2150 550);
DISPLAY INVISIBLE (-2150 550);
FORCEPROP 1 LAST SIZE 1B
J 0
(-2075 500);
DISPLAY 1.170213 (-2075 500);
PAINT GREEN (-2075 500);
DISPLAY INVISIBLE (-2075 500);
FORCEPROP 2 LAST CDS_LIB mstr_symbols
J 0
(-2150 550);
PAINT ORANGE (-2150 550);
DISPLAY INVISIBLE (-2150 550);
FORCEPROP 1 LAST PATH I67
J 0
(-2075 550);
DISPLAY 0.872340 (-2075 550);
PAINT AQUA (-2075 550);
DISPLAY INVISIBLE (-2075 550);
FORCEPROP 2 LAST ROOM PROCHOT_MEMHOT_ISO
J 0
(-2525 625);
PAINT ORANGE (-2525 625);
DISPLAY INVISIBLE (-2525 625);
FORCEPROP 1 LAST BODY_TYPE PLUMBING
J 0
(-2195 507);
DISPLAY 0.340426 (-2195 507);
PAINT GREEN (-2195 507);
DISPLAY INVISIBLE (-2195 507);
FORCEPROP 1 LAST HDL_POWER GND
J 0
(-2150 700);
DISPLAY 1.170213 (-2150 700);
PAINT GREEN (-2150 700);
DISPLAY INVISIBLE (-2150 700);
FORCEADD OFFPAGE..1
(-3325 725);
FORCEPROP 2 LAST $XR2 146 
J 0
(-3577 689);
DISPLAY 0.638298 (-3577 689);
PAINT MONO (-3577 689);
FORCEPROP 2 LAST $XR1 119 
J 0
(-3697 725);
DISPLAY 0.638298 (-3697 725);
PAINT MONO (-3697 725);
FORCEPROP 2 LAST $XR0 218 
J 0
(-3577 725);
DISPLAY 0.638298 (-3577 725);
PAINT MONO (-3577 725);
FORCEPROP 2 LAST CDS_LIB mstr_standard
J 0
(-3325 725);
PAINT ORANGE (-3325 725);
DISPLAY INVISIBLE (-3325 725);
FORCEPROP 2 LAST ROOM PROCHOT_MEMHOT_ISO
J 0
(-3575 775);
DISPLAY 0.978723 (-3575 775);
PAINT ORANGE (-3575 775);
DISPLAY INVISIBLE (-3575 775);
FORCEPROP 2 LAST PATH I68
J 0
(-3575 775);
DISPLAY 1.021277 (-3575 775);
PAINT ORANGE (-3575 775);
DISPLAY INVISIBLE (-3575 775);
FORCEPROP 1 LAST OFFPAGE TRUE
J 0
(-3000 600);
PAINT GREEN (-3000 600);
DISPLAY INVISIBLE (-3000 600);
FORCEPROP 1 LAST COMMENT_BODY TRUE
J 0
(-3200 625);
DISPLAY 0.978723 (-3200 625);
PAINT PEACH (-3200 625);
DISPLAY INVISIBLE (-3200 625);
FORCEADD FET_N_DUAL..5
(1175 1975);
FORCEPROP 1 LAST LOCATION Q7E2
J 0
(1300 1800);
DISPLAY 0.617021 (1300 1800);
PAINT AQUA (1300 1800);
FORCEPROP 1 LAST PART_NUMBER E40049-001
J 0
(1300 1650);
DISPLAY 0.617021 (1300 1650);
PAINT BLUE (1300 1650);
FORCEPROP 1 LAST VALUE NTJD4001N
J 0
(1300 1750);
DISPLAY 0.617021 (1300 1750);
PAINT SKYBLUE (1300 1750);
FORCEPROP 1 LAST MATERIAL FET
J 0
(1300 1700);
DISPLAY 0.617021 (1300 1700);
PAINT SKYBLUE (1300 1700);
FORCEPROP 1 LASTPIN (1175 1775) $PN 1
J 2
(1233 1775);
DISPLAY 0.617021 (1233 1775);
PAINT MONO (1233 1775);
FORCEPROP 1 LASTPIN (975 1875) $PN 2
J 2
(978 1890);
DISPLAY 0.617021 (978 1890);
PAINT MONO (978 1890);
FORCEPROP 1 LASTPIN (1175 2175) $PN 6
J 2
(1228 2140);
DISPLAY 0.617021 (1228 2140);
PAINT MONO (1228 2140);
FORCEPROP 1 LAST PACK_TYPE SMLF
J 0
(1375 1825);
PAINT SKYBLUE (1375 1825);
DISPLAY INVISIBLE (1375 1825);
FORCEPROP 2 LAST SEC_TYPE SMLF
J 0
(1375 2075);
DISPLAY 1.404255 (1375 2075);
PAINT ORANGE (1375 2075);
DISPLAY INVISIBLE (1375 2075);
FORCEPROP 2 LAST CDS_LIB mstr_discrete
J 0
(1175 1975);
PAINT ORANGE (1175 1975);
DISPLAY INVISIBLE (1175 1975);
FORCEPROP 2 LAST SEC 1
J 0
(1375 2075);
DISPLAY 0.936170 (1375 2075);
PAINT MONO (1375 2075);
DISPLAY INVISIBLE (1375 2075);
FORCEPROP 2 LAST CDS_LOCATION Q7E2
J 0
(1300 1800);
DISPLAY 0.617021 (1300 1800);
PAINT AQUA (1300 1800);
DISPLAY INVISIBLE (1300 1800);
FORCEPROP 1 LAST PATH I69
J 0
(1375 2025);
DISPLAY 0.978723 (1375 2025);
PAINT BLUE (1375 2025);
DISPLAY INVISIBLE (1375 2025);
FORCEPROP 2 LAST ROOM PROC_SIDEBAND
J 0
(1175 2015);
DISPLAY 0.787234 (1175 2015);
PAINT SKYBLUE (1175 2015);
DISPLAY INVISIBLE (1175 2015);
FORCEADD OFFPAGE..5
R 2
(2650 2350);
FORCEPROP 2 LAST $XR2 152 
J 0
(3019 2350);
DISPLAY 0.638298 (3019 2350);
PAINT MONO (3019 2350);
FORCEPROP 2 LAST $XR1 95 
J 0
(2929 2350);
DISPLAY 0.638298 (2929 2350);
PAINT MONO (2929 2350);
FORCEPROP 2 LAST $XR0 55 
J 0
(2839 2350);
DISPLAY 0.638298 (2839 2350);
PAINT MONO (2839 2350);
FORCEPROP 2 LAST CDS_LIB mstr_standard
J 1
(2650 2350);
PAINT ORANGE (2650 2350);
DISPLAY INVISIBLE (2650 2350);
FORCEPROP 2 LAST ROOM PROCHOT_MEMHOT_ISO
J 2
(2960 2380);
DISPLAY 0.978723 (2960 2380);
PAINT ORANGE (2960 2380);
DISPLAY INVISIBLE (2960 2380);
FORCEPROP 2 LAST PATH I70
J 0
(2945 2400);
DISPLAY 1.021277 (2945 2400);
PAINT ORANGE (2945 2400);
DISPLAY INVISIBLE (2945 2400);
FORCEPROP 1 LAST OFFPAGE TRUE
J 2
(2325 2225);
PAINT GREEN (2325 2225);
DISPLAY INVISIBLE (2325 2225);
FORCEPROP 1 LAST COMMENT_BODY TRUE
J 2
(2550 2275);
DISPLAY 0.978723 (2550 2275);
PAINT GREEN (2550 2275);
DISPLAY INVISIBLE (2550 2275);
FORCEADD OFFPAGE..5
R 2
(2650 1250);
FORCEPROP 2 LAST $XR2 152 
J 0
(3019 1250);
DISPLAY 0.638298 (3019 1250);
PAINT MONO (3019 1250);
FORCEPROP 2 LAST $XR1 95 
J 0
(2929 1250);
DISPLAY 0.638298 (2929 1250);
PAINT MONO (2929 1250);
FORCEPROP 2 LAST $XR0 55 
J 0
(2839 1250);
DISPLAY 0.638298 (2839 1250);
PAINT MONO (2839 1250);
FORCEPROP 2 LAST CDS_LIB mstr_standard
J 1
(2650 1250);
PAINT ORANGE (2650 1250);
DISPLAY INVISIBLE (2650 1250);
FORCEPROP 2 LAST ROOM PROCHOT_MEMHOT_ISO
J 2
(2960 1280);
DISPLAY 0.978723 (2960 1280);
PAINT ORANGE (2960 1280);
DISPLAY INVISIBLE (2960 1280);
FORCEPROP 2 LAST PATH I71
J 0
(2945 1300);
DISPLAY 1.021277 (2945 1300);
PAINT ORANGE (2945 1300);
DISPLAY INVISIBLE (2945 1300);
FORCEPROP 1 LAST OFFPAGE TRUE
J 2
(2325 1125);
PAINT GREEN (2325 1125);
DISPLAY INVISIBLE (2325 1125);
FORCEPROP 1 LAST COMMENT_BODY TRUE
J 2
(2550 1175);
DISPLAY 0.978723 (2550 1175);
PAINT GREEN (2550 1175);
DISPLAY INVISIBLE (2550 1175);
FORCEADD GND..1
(1900 1800);
FORCEPROP 3 LASTPIN (1900 1850) SIG_NAME GND\g
J 0
(1910 1860);
DISPLAY 0.659574 (1910 1860);
PAINT MONO (1910 1860);
DISPLAY INVISIBLE (1910 1860);
FORCEPROP 1 LAST VOLTAGE 0
J 0
(1900 1800);
PAINT SKYBLUE (1900 1800);
DISPLAY INVISIBLE (1900 1800);
FORCEPROP 2 LAST CDS_LIB mstr_symbols
J 0
(1900 1800);
PAINT ORANGE (1900 1800);
DISPLAY INVISIBLE (1900 1800);
FORCEPROP 1 LAST SIZE 1B
J 0
(1975 1750);
DISPLAY 1.170213 (1975 1750);
PAINT GREEN (1975 1750);
DISPLAY INVISIBLE (1975 1750);
FORCEPROP 1 LAST PATH I74
J 0
(1975 1800);
DISPLAY 0.872340 (1975 1800);
PAINT AQUA (1975 1800);
DISPLAY INVISIBLE (1975 1800);
FORCEPROP 2 LAST ROOM PROCHOT_MEMHOT_ISO
J 0
(1525 1875);
PAINT ORANGE (1525 1875);
DISPLAY INVISIBLE (1525 1875);
FORCEPROP 1 LAST BODY_TYPE PLUMBING
J 0
(1855 1757);
DISPLAY 0.340426 (1855 1757);
PAINT GREEN (1855 1757);
DISPLAY INVISIBLE (1855 1757);
FORCEPROP 1 LAST HDL_POWER GND
J 0
(1900 1950);
DISPLAY 1.170213 (1900 1950);
PAINT GREEN (1900 1950);
DISPLAY INVISIBLE (1900 1950);
FORCEADD FET_N_DUAL..5
(1900 2100);
FORCEPROP 1 LAST LOCATION Q7E2
J 0
(2050 1950);
DISPLAY 0.617021 (2050 1950);
PAINT AQUA (2050 1950);
FORCEPROP 1 LAST MATERIAL FET
J 0
(2050 1850);
DISPLAY 0.617021 (2050 1850);
PAINT SKYBLUE (2050 1850);
FORCEPROP 1 LASTPIN (1900 1900) $PN 4
J 2
(1958 1900);
DISPLAY 0.617021 (1958 1900);
PAINT MONO (1958 1900);
FORCEPROP 1 LASTPIN (1700 2000) $PN 5
J 2
(1703 2015);
DISPLAY 0.617021 (1703 2015);
PAINT MONO (1703 2015);
FORCEPROP 1 LASTPIN (1900 2300) $PN 3
J 2
(1953 2265);
DISPLAY 0.617021 (1953 2265);
PAINT MONO (1953 2265);
FORCEPROP 1 LAST PART_NUMBER E40049-001
J 0
(2050 1800);
DISPLAY 0.617021 (2050 1800);
PAINT BLUE (2050 1800);
FORCEPROP 1 LAST VALUE NTJD4001N
J 0
(2050 1900);
DISPLAY 0.617021 (2050 1900);
PAINT SKYBLUE (2050 1900);
FORCEPROP 1 LAST PACK_TYPE SMLF
J 0
(2100 1950);
PAINT SKYBLUE (2100 1950);
DISPLAY INVISIBLE (2100 1950);
FORCEPROP 2 LAST SEC_TYPE SMLF
J 0
(2100 2200);
DISPLAY 1.404255 (2100 2200);
PAINT ORANGE (2100 2200);
DISPLAY INVISIBLE (2100 2200);
FORCEPROP 2 LAST CDS_LIB mstr_discrete
J 0
(1900 2100);
PAINT ORANGE (1900 2100);
DISPLAY INVISIBLE (1900 2100);
FORCEPROP 2 LAST SEC 2
J 0
(2100 2200);
DISPLAY 0.936170 (2100 2200);
PAINT MONO (2100 2200);
DISPLAY INVISIBLE (2100 2200);
FORCEPROP 2 LAST CDS_LOCATION Q7E2
J 0
(2050 1950);
DISPLAY 0.617021 (2050 1950);
PAINT AQUA (2050 1950);
DISPLAY INVISIBLE (2050 1950);
FORCEPROP 1 LAST PATH I75
J 0
(2100 2150);
DISPLAY 0.978723 (2100 2150);
PAINT BLUE (2100 2150);
DISPLAY INVISIBLE (2100 2150);
FORCEPROP 2 LAST ROOM PROC_SIDEBAND
J 0
(1900 2140);
DISPLAY 0.787234 (1900 2140);
PAINT SKYBLUE (1900 2140);
DISPLAY INVISIBLE (1900 2140);
FORCEADD GND..1
(1900 700);
FORCEPROP 3 LASTPIN (1900 750) SIG_NAME GND\g
J 0
(1910 760);
DISPLAY 0.659574 (1910 760);
PAINT MONO (1910 760);
DISPLAY INVISIBLE (1910 760);
FORCEPROP 1 LAST VOLTAGE 0
J 0
(1900 700);
PAINT SKYBLUE (1900 700);
DISPLAY INVISIBLE (1900 700);
FORCEPROP 2 LAST CDS_LIB mstr_symbols
J 0
(1900 700);
PAINT ORANGE (1900 700);
DISPLAY INVISIBLE (1900 700);
FORCEPROP 1 LAST SIZE 1B
J 0
(1975 650);
DISPLAY 1.170213 (1975 650);
PAINT GREEN (1975 650);
DISPLAY INVISIBLE (1975 650);
FORCEPROP 1 LAST PATH I76
J 0
(1975 700);
DISPLAY 0.872340 (1975 700);
PAINT AQUA (1975 700);
DISPLAY INVISIBLE (1975 700);
FORCEPROP 2 LAST ROOM PROCHOT_MEMHOT_ISO
J 0
(1525 775);
PAINT ORANGE (1525 775);
DISPLAY INVISIBLE (1525 775);
FORCEPROP 1 LAST BODY_TYPE PLUMBING
J 0
(1855 657);
DISPLAY 0.340426 (1855 657);
PAINT GREEN (1855 657);
DISPLAY INVISIBLE (1855 657);
FORCEPROP 1 LAST HDL_POWER GND
J 0
(1900 850);
DISPLAY 1.170213 (1900 850);
PAINT GREEN (1900 850);
DISPLAY INVISIBLE (1900 850);
FORCEADD FET_N_DUAL..5
(1900 1000);
FORCEPROP 1 LAST LOCATION Q4B1
J 0
(2050 850);
DISPLAY 0.617021 (2050 850);
PAINT AQUA (2050 850);
FORCEPROP 1 LAST VALUE NTJD4001N
J 0
(2050 800);
DISPLAY 0.617021 (2050 800);
PAINT SKYBLUE (2050 800);
FORCEPROP 1 LAST MATERIAL FET
J 0
(2050 750);
DISPLAY 0.617021 (2050 750);
PAINT SKYBLUE (2050 750);
FORCEPROP 1 LASTPIN (1900 800) $PN 4
J 2
(1958 800);
DISPLAY 0.617021 (1958 800);
PAINT MONO (1958 800);
FORCEPROP 1 LASTPIN (1700 900) $PN 5
J 2
(1703 915);
DISPLAY 0.617021 (1703 915);
PAINT MONO (1703 915);
FORCEPROP 1 LASTPIN (1900 1200) $PN 3
J 2
(1953 1165);
DISPLAY 0.617021 (1953 1165);
PAINT MONO (1953 1165);
FORCEPROP 1 LAST PART_NUMBER E40049-001
J 0
(2050 700);
DISPLAY 0.617021 (2050 700);
PAINT BLUE (2050 700);
FORCEPROP 1 LAST PACK_TYPE SMLF
J 0
(2100 850);
PAINT SKYBLUE (2100 850);
DISPLAY INVISIBLE (2100 850);
FORCEPROP 2 LAST SEC_TYPE SMLF
J 0
(2100 1100);
DISPLAY 1.404255 (2100 1100);
PAINT ORANGE (2100 1100);
DISPLAY INVISIBLE (2100 1100);
FORCEPROP 2 LAST CDS_LIB mstr_discrete
J 0
(1900 1000);
PAINT ORANGE (1900 1000);
DISPLAY INVISIBLE (1900 1000);
FORCEPROP 2 LAST SEC 2
J 0
(2100 1100);
DISPLAY 0.936170 (2100 1100);
PAINT MONO (2100 1100);
DISPLAY INVISIBLE (2100 1100);
FORCEPROP 2 LAST CDS_LOCATION Q4B1
J 0
(2050 850);
DISPLAY 0.617021 (2050 850);
PAINT AQUA (2050 850);
DISPLAY INVISIBLE (2050 850);
FORCEPROP 1 LAST PATH I77
J 0
(2100 1050);
DISPLAY 0.978723 (2100 1050);
PAINT BLUE (2100 1050);
DISPLAY INVISIBLE (2100 1050);
FORCEPROP 2 LAST ROOM PROC_SIDEBAND
J 0
(1900 1040);
DISPLAY 0.787234 (1900 1040);
PAINT SKYBLUE (1900 1040);
DISPLAY INVISIBLE (1900 1040);
FORCEADD P3V3..1
(1175 2625);
FORCEPROP 3 LASTPIN (1175 2575) SIG_NAME P3V3\g
J 0
(1185 2585);
DISPLAY 0.659574 (1185 2585);
PAINT MONO (1185 2585);
DISPLAY INVISIBLE (1185 2585);
FORCEPROP 1 LAST VOLTAGE +3.3
J 0
(1175 2625);
PAINT SKYBLUE (1175 2625);
DISPLAY INVISIBLE (1175 2625);
FORCEPROP 2 LAST CDS_LIB mstr_symbols
J 0
(1175 2625);
PAINT ORANGE (1175 2625);
DISPLAY INVISIBLE (1175 2625);
FORCEPROP 1 LAST SIZE 1B
J 0
(1220 2647);
DISPLAY 0.553191 (1220 2647);
PAINT GREEN (1220 2647);
DISPLAY INVISIBLE (1220 2647);
FORCEPROP 1 LAST PATH I78
J 0
(1220 2627);
DISPLAY 0.340426 (1220 2627);
PAINT GREEN (1220 2627);
DISPLAY INVISIBLE (1220 2627);
FORCEPROP 2 LAST ROOM PROCHOT_MEMHOT_ISO
J 0
(1025 2725);
PAINT PEACH (1025 2725);
DISPLAY INVISIBLE (1025 2725);
FORCEPROP 1 LAST BODY_TYPE PLUMBING
J 0
(1130 2582);
DISPLAY 0.468085 (1130 2582);
PAINT GREEN (1130 2582);
DISPLAY INVISIBLE (1130 2582);
FORCEPROP 1 LAST HDL_POWER P3V3
J 0
(850 2500);
DISPLAY 1.170213 (850 2500);
PAINT GREEN (850 2500);
DISPLAY INVISIBLE (850 2500);
FORCEADD RES..2
R 2
(1175 2425);
FORCEPROP 1 LAST LOCATION R3R10
J 2
(1130 2500);
DISPLAY 0.617021 (1130 2500);
PAINT AQUA (1130 2500);
FORCEPROP 1 LAST VALUE 4.75K
J 2
(1130 2450);
DISPLAY 0.617021 (1130 2450);
PAINT SKYBLUE (1130 2450);
FORCEPROP 1 LAST TOLERANCE 1%
J 2
(1130 2400);
DISPLAY 0.617021 (1130 2400);
PAINT SKYBLUE (1130 2400);
FORCEPROP 1 LASTPIN (1175 2325) $PN 2
J 2
(1170 2335);
DISPLAY 0.617021 (1170 2335);
PAINT MONO (1170 2335);
FORCEPROP 1 LASTPIN (1175 2525) $PN 1
J 2
(1170 2487);
DISPLAY 0.617021 (1170 2487);
PAINT MONO (1170 2487);
FORCEPROP 1 LAST PART_NUMBER G21796-072
R 1
J 0
(1235 2300);
DISPLAY 0.617021 (1235 2300);
PAINT BLUE (1235 2300);
FORCEPROP 1 LAST WATTAGE 1/16W
J 2
(1135 2350);
DISPLAY 0.617021 (1135 2350);
PAINT SKYBLUE (1135 2350);
FORCEPROP 1 LAST MATERIAL CHIP
J 2
(1135 2300);
DISPLAY 0.617021 (1135 2300);
PAINT SKYBLUE (1135 2300);
FORCEPROP 1 LAST PACK_TYPE 0402
J 2
(1135 2250);
DISPLAY 0.617021 (1135 2250);
PAINT SKYBLUE (1135 2250);
FORCEPROP 2 LAST BOM_COST PROC_SIDEBAND
J 0
(1175 2425);
PAINT MONO (1175 2425);
DISPLAY INVISIBLE (1175 2425);
FORCEPROP 2 LAST CDS_LIB mstr_discrete
J 2
(1175 2425);
DISPLAY 1.361702 (1175 2425);
PAINT ORANGE (1175 2425);
DISPLAY INVISIBLE (1175 2425);
FORCEPROP 2 LAST CDS_SEC 1
J 1
(1125 2650);
DISPLAY 1.404255 (1125 2650);
PAINT ORANGE (1125 2650);
DISPLAY INVISIBLE (1125 2650);
FORCEPROP 2 LAST $SEC 1
J 1
(1125 2650);
DISPLAY 0.936170 (1125 2650);
PAINT MONO (1125 2650);
DISPLAY INVISIBLE (1125 2650);
FORCEPROP 2 LAST CDS_LOCATION R3R10
J 2
(1130 2500);
DISPLAY 0.617021 (1130 2500);
PAINT AQUA (1130 2500);
DISPLAY INVISIBLE (1130 2500);
FORCEPROP 1 LAST PATH I79
J 2
(1125 2600);
DISPLAY 0.978723 (1125 2600);
PAINT WHITE (1125 2600);
DISPLAY INVISIBLE (1125 2600);
FORCEPROP 2 LAST ROOM PROC_SIDEBAND
J 2
(1125 2600);
PAINT PEACH (1125 2600);
DISPLAY INVISIBLE (1125 2600);
FORCEADD GND..1
(1175 1700);
FORCEPROP 3 LASTPIN (1175 1750) SIG_NAME GND\g
J 0
(1185 1760);
DISPLAY 0.659574 (1185 1760);
PAINT MONO (1185 1760);
DISPLAY INVISIBLE (1185 1760);
FORCEPROP 1 LAST VOLTAGE 0
J 0
(1175 1700);
PAINT SKYBLUE (1175 1700);
DISPLAY INVISIBLE (1175 1700);
FORCEPROP 2 LAST CDS_LIB mstr_symbols
J 0
(1175 1700);
PAINT ORANGE (1175 1700);
DISPLAY INVISIBLE (1175 1700);
FORCEPROP 1 LAST SIZE 1B
J 0
(1250 1650);
DISPLAY 1.170213 (1250 1650);
PAINT GREEN (1250 1650);
DISPLAY INVISIBLE (1250 1650);
FORCEPROP 1 LAST PATH I80
J 0
(1250 1700);
DISPLAY 0.872340 (1250 1700);
PAINT AQUA (1250 1700);
DISPLAY INVISIBLE (1250 1700);
FORCEPROP 2 LAST ROOM PROCHOT_MEMHOT_ISO
J 0
(800 1775);
PAINT ORANGE (800 1775);
DISPLAY INVISIBLE (800 1775);
FORCEPROP 1 LAST BODY_TYPE PLUMBING
J 0
(1130 1657);
DISPLAY 0.340426 (1130 1657);
PAINT GREEN (1130 1657);
DISPLAY INVISIBLE (1130 1657);
FORCEPROP 1 LAST HDL_POWER GND
J 0
(1175 1850);
DISPLAY 1.170213 (1175 1850);
PAINT GREEN (1175 1850);
DISPLAY INVISIBLE (1175 1850);
FORCEADD P3V3..1
(1175 1525);
FORCEPROP 3 LASTPIN (1175 1475) SIG_NAME P3V3\g
J 0
(1185 1485);
DISPLAY 0.659574 (1185 1485);
PAINT MONO (1185 1485);
DISPLAY INVISIBLE (1185 1485);
FORCEPROP 1 LAST VOLTAGE +3.3
J 0
(1175 1525);
PAINT SKYBLUE (1175 1525);
DISPLAY INVISIBLE (1175 1525);
FORCEPROP 2 LAST CDS_LIB mstr_symbols
J 0
(1175 1525);
PAINT ORANGE (1175 1525);
DISPLAY INVISIBLE (1175 1525);
FORCEPROP 1 LAST SIZE 1B
J 0
(1220 1547);
DISPLAY 0.553191 (1220 1547);
PAINT GREEN (1220 1547);
DISPLAY INVISIBLE (1220 1547);
FORCEPROP 1 LAST PATH I81
J 0
(1220 1527);
DISPLAY 0.340426 (1220 1527);
PAINT GREEN (1220 1527);
DISPLAY INVISIBLE (1220 1527);
FORCEPROP 2 LAST ROOM PROCHOT_MEMHOT_ISO
J 0
(1025 1625);
PAINT PEACH (1025 1625);
DISPLAY INVISIBLE (1025 1625);
FORCEPROP 1 LAST BODY_TYPE PLUMBING
J 0
(1130 1482);
DISPLAY 0.468085 (1130 1482);
PAINT GREEN (1130 1482);
DISPLAY INVISIBLE (1130 1482);
FORCEPROP 1 LAST HDL_POWER P3V3
J 0
(850 1400);
DISPLAY 1.170213 (850 1400);
PAINT GREEN (850 1400);
DISPLAY INVISIBLE (850 1400);
FORCEADD RES..2
R 2
(1175 1325);
FORCEPROP 1 LAST LOCATION R6M4
J 2
(1130 1400);
DISPLAY 0.617021 (1130 1400);
PAINT AQUA (1130 1400);
FORCEPROP 1 LAST PART_NUMBER G21796-072
R 1
J 0
(1235 1200);
DISPLAY 0.617021 (1235 1200);
PAINT BLUE (1235 1200);
FORCEPROP 1 LAST VALUE 4.75K
J 2
(1130 1350);
DISPLAY 0.617021 (1130 1350);
PAINT SKYBLUE (1130 1350);
FORCEPROP 1 LAST TOLERANCE 1%
J 2
(1130 1300);
DISPLAY 0.617021 (1130 1300);
PAINT SKYBLUE (1130 1300);
FORCEPROP 1 LAST PACK_TYPE 0402
J 2
(1135 1150);
DISPLAY 0.617021 (1135 1150);
PAINT SKYBLUE (1135 1150);
FORCEPROP 1 LAST MATERIAL CHIP
J 2
(1135 1200);
DISPLAY 0.617021 (1135 1200);
PAINT SKYBLUE (1135 1200);
FORCEPROP 1 LAST WATTAGE 1/16W
J 2
(1135 1250);
DISPLAY 0.617021 (1135 1250);
PAINT SKYBLUE (1135 1250);
FORCEPROP 1 LASTPIN (1175 1225) $PN 2
J 2
(1170 1235);
DISPLAY 0.617021 (1170 1235);
PAINT MONO (1170 1235);
FORCEPROP 1 LASTPIN (1175 1425) $PN 1
J 2
(1170 1387);
DISPLAY 0.617021 (1170 1387);
PAINT MONO (1170 1387);
FORCEPROP 2 LAST BOM_COST PROC_SIDEBAND
J 0
(1175 1325);
PAINT MONO (1175 1325);
DISPLAY INVISIBLE (1175 1325);
FORCEPROP 2 LAST CDS_LIB mstr_discrete
J 2
(1175 1325);
DISPLAY 1.361702 (1175 1325);
PAINT ORANGE (1175 1325);
DISPLAY INVISIBLE (1175 1325);
FORCEPROP 2 LAST CDS_SEC 1
J 1
(1125 1550);
DISPLAY 1.404255 (1125 1550);
PAINT ORANGE (1125 1550);
DISPLAY INVISIBLE (1125 1550);
FORCEPROP 2 LAST $SEC 1
J 1
(1125 1550);
DISPLAY 0.936170 (1125 1550);
PAINT MONO (1125 1550);
DISPLAY INVISIBLE (1125 1550);
FORCEPROP 2 LAST CDS_LOCATION R6M4
J 2
(1130 1400);
DISPLAY 0.617021 (1130 1400);
PAINT AQUA (1130 1400);
DISPLAY INVISIBLE (1130 1400);
FORCEPROP 1 LAST PATH I82
J 2
(1125 1500);
DISPLAY 0.978723 (1125 1500);
PAINT WHITE (1125 1500);
DISPLAY INVISIBLE (1125 1500);
FORCEPROP 2 LAST ROOM PROC_SIDEBAND
J 2
(1125 1500);
PAINT PEACH (1125 1500);
DISPLAY INVISIBLE (1125 1500);
FORCEADD GND..1
(1175 600);
FORCEPROP 3 LASTPIN (1175 650) SIG_NAME GND\g
J 0
(1185 660);
DISPLAY 0.659574 (1185 660);
PAINT MONO (1185 660);
DISPLAY INVISIBLE (1185 660);
FORCEPROP 1 LAST VOLTAGE 0
J 0
(1175 600);
PAINT SKYBLUE (1175 600);
DISPLAY INVISIBLE (1175 600);
FORCEPROP 2 LAST CDS_LIB mstr_symbols
J 0
(1175 600);
PAINT ORANGE (1175 600);
DISPLAY INVISIBLE (1175 600);
FORCEPROP 1 LAST SIZE 1B
J 0
(1250 550);
DISPLAY 1.170213 (1250 550);
PAINT GREEN (1250 550);
DISPLAY INVISIBLE (1250 550);
FORCEPROP 1 LAST PATH I83
J 0
(1250 600);
DISPLAY 0.872340 (1250 600);
PAINT AQUA (1250 600);
DISPLAY INVISIBLE (1250 600);
FORCEPROP 2 LAST ROOM PROCHOT_MEMHOT_ISO
J 0
(800 675);
PAINT ORANGE (800 675);
DISPLAY INVISIBLE (800 675);
FORCEPROP 1 LAST BODY_TYPE PLUMBING
J 0
(1130 557);
DISPLAY 0.340426 (1130 557);
PAINT GREEN (1130 557);
DISPLAY INVISIBLE (1130 557);
FORCEPROP 1 LAST HDL_POWER GND
J 0
(1175 750);
DISPLAY 1.170213 (1175 750);
PAINT GREEN (1175 750);
DISPLAY INVISIBLE (1175 750);
FORCEADD FET_N_DUAL..5
(1175 875);
FORCEPROP 1 LAST MATERIAL FET
J 0
(1300 600);
DISPLAY 0.617021 (1300 600);
PAINT SKYBLUE (1300 600);
FORCEPROP 1 LASTPIN (1175 675) $PN 1
J 2
(1233 675);
DISPLAY 0.617021 (1233 675);
PAINT MONO (1233 675);
FORCEPROP 1 LASTPIN (975 775) $PN 2
J 2
(978 790);
DISPLAY 0.617021 (978 790);
PAINT MONO (978 790);
FORCEPROP 1 LASTPIN (1175 1075) $PN 6
J 2
(1228 1040);
DISPLAY 0.617021 (1228 1040);
PAINT MONO (1228 1040);
FORCEPROP 1 LAST LOCATION Q4B1
J 0
(1300 700);
DISPLAY 0.617021 (1300 700);
PAINT AQUA (1300 700);
FORCEPROP 1 LAST VALUE NTJD4001N
J 0
(1300 650);
DISPLAY 0.617021 (1300 650);
PAINT SKYBLUE (1300 650);
FORCEPROP 1 LAST PART_NUMBER E40049-001
J 0
(1300 550);
DISPLAY 0.617021 (1300 550);
PAINT BLUE (1300 550);
FORCEPROP 1 LAST PACK_TYPE SMLF
J 0
(1375 725);
PAINT SKYBLUE (1375 725);
DISPLAY INVISIBLE (1375 725);
FORCEPROP 2 LAST SEC_TYPE SMLF
J 0
(1375 975);
DISPLAY 1.404255 (1375 975);
PAINT ORANGE (1375 975);
DISPLAY INVISIBLE (1375 975);
FORCEPROP 2 LAST CDS_LIB mstr_discrete
J 0
(1175 875);
PAINT ORANGE (1175 875);
DISPLAY INVISIBLE (1175 875);
FORCEPROP 2 LAST SEC 1
J 0
(1375 975);
DISPLAY 0.936170 (1375 975);
PAINT MONO (1375 975);
DISPLAY INVISIBLE (1375 975);
FORCEPROP 2 LAST CDS_LOCATION Q4B1
J 0
(1300 700);
DISPLAY 0.617021 (1300 700);
PAINT AQUA (1300 700);
DISPLAY INVISIBLE (1300 700);
FORCEPROP 1 LAST PATH I84
J 0
(1375 925);
DISPLAY 0.978723 (1375 925);
PAINT BLUE (1375 925);
DISPLAY INVISIBLE (1375 925);
FORCEPROP 2 LAST ROOM PROC_SIDEBAND
J 0
(1175 915);
DISPLAY 0.787234 (1175 915);
PAINT SKYBLUE (1175 915);
DISPLAY INVISIBLE (1175 915);
FORCEADD OFFPAGE..1
(0 1875);
FORCEPROP 2 LAST $XR2 144 
J 0
(-522 1875);
DISPLAY 0.638298 (-522 1875);
PAINT MONO (-522 1875);
FORCEPROP 2 LAST $XR1 119 
J 0
(-402 1875);
DISPLAY 0.638298 (-402 1875);
PAINT MONO (-402 1875);
FORCEPROP 2 LAST $XR0 223 
J 0
(-282 1875);
DISPLAY 0.638298 (-282 1875);
PAINT MONO (-282 1875);
FORCEPROP 2 LAST ROOM PROCHOT_MEMHOT_ISO
J 0
(-250 1925);
DISPLAY 0.978723 (-250 1925);
PAINT ORANGE (-250 1925);
DISPLAY INVISIBLE (-250 1925);
FORCEPROP 2 LAST CDS_LIB mstr_standard
J 0
(0 1875);
PAINT ORANGE (0 1875);
DISPLAY INVISIBLE (0 1875);
FORCEPROP 2 LAST PATH I85
J 0
(-250 1925);
DISPLAY 1.021277 (-250 1925);
PAINT ORANGE (-250 1925);
DISPLAY INVISIBLE (-250 1925);
FORCEPROP 1 LAST OFFPAGE TRUE
J 0
(325 1750);
PAINT GREEN (325 1750);
DISPLAY INVISIBLE (325 1750);
FORCEPROP 1 LAST COMMENT_BODY TRUE
J 0
(125 1775);
DISPLAY 0.978723 (125 1775);
PAINT PEACH (125 1775);
DISPLAY INVISIBLE (125 1775);
FORCEADD OFFPAGE..1
(0 775);
FORCEPROP 2 LAST $XR2 145 
J 0
(-522 775);
DISPLAY 0.638298 (-522 775);
PAINT MONO (-522 775);
FORCEPROP 2 LAST $XR1 119 
J 0
(-402 775);
DISPLAY 0.638298 (-402 775);
PAINT MONO (-402 775);
FORCEPROP 2 LAST $XR0 226 
J 0
(-282 775);
DISPLAY 0.638298 (-282 775);
PAINT MONO (-282 775);
FORCEPROP 2 LAST ROOM PROCHOT_MEMHOT_ISO
J 0
(-250 825);
DISPLAY 0.978723 (-250 825);
PAINT ORANGE (-250 825);
DISPLAY INVISIBLE (-250 825);
FORCEPROP 2 LAST CDS_LIB mstr_standard
J 0
(0 775);
PAINT ORANGE (0 775);
DISPLAY INVISIBLE (0 775);
FORCEPROP 2 LAST PATH I86
J 0
(-250 825);
DISPLAY 1.021277 (-250 825);
PAINT ORANGE (-250 825);
DISPLAY INVISIBLE (-250 825);
FORCEPROP 1 LAST OFFPAGE TRUE
J 0
(325 650);
PAINT GREEN (325 650);
DISPLAY INVISIBLE (325 650);
FORCEPROP 1 LAST COMMENT_BODY TRUE
J 0
(125 675);
DISPLAY 0.978723 (125 675);
PAINT PEACH (125 675);
DISPLAY INVISIBLE (125 675);
FORCEADD FET_N_DUAL..5
(-1425 2050);
FORCEPROP 1 LAST LOCATION Q3U1
J 0
(-1225 2050);
DISPLAY 0.617021 (-1225 2050);
PAINT AQUA (-1225 2050);
FORCEPROP 1 LASTPIN (-1425 1850) $PN 4
J 2
(-1367 1850);
DISPLAY 0.617021 (-1367 1850);
PAINT WHITE (-1367 1850);
FORCEPROP 1 LASTPIN (-1625 1950) $PN 5
J 2
(-1622 1965);
DISPLAY 0.617021 (-1622 1965);
PAINT WHITE (-1622 1965);
FORCEPROP 1 LASTPIN (-1425 2250) $PN 3
J 2
(-1372 2215);
DISPLAY 0.617021 (-1372 2215);
PAINT WHITE (-1372 2215);
FORCEPROP 1 LAST VALUE NTJD4001N
J 0
(-1225 2000);
DISPLAY 0.617021 (-1225 2000);
PAINT SKYBLUE (-1225 2000);
FORCEPROP 1 LAST MATERIAL FET
J 0
(-1225 1950);
DISPLAY 0.617021 (-1225 1950);
PAINT SKYBLUE (-1225 1950);
FORCEPROP 1 LAST PART_NUMBER E40049-001
J 0
(-1225 1900);
DISPLAY 0.617021 (-1225 1900);
PAINT BLUE (-1225 1900);
FORCEPROP 1 LAST PACK_TYPE SMLF
J 0
(-1225 1900);
PAINT SKYBLUE (-1225 1900);
DISPLAY INVISIBLE (-1225 1900);
FORCEPROP 2 LAST SEC_TYPE SMLF
J 0
(-1225 2150);
DISPLAY 1.021277 (-1225 2150);
PAINT ORANGE (-1225 2150);
DISPLAY INVISIBLE (-1225 2150);
FORCEPROP 2 LAST CDS_LIB mstr_discrete
J 0
(-1425 2050);
PAINT ORANGE (-1425 2050);
DISPLAY INVISIBLE (-1425 2050);
FORCEPROP 2 LAST SEC 2
J 0
(-1225 2150);
DISPLAY 0.680851 (-1225 2150);
PAINT MONO (-1225 2150);
DISPLAY INVISIBLE (-1225 2150);
FORCEPROP 2 LAST CDS_LOCATION Q3U1
J 0
(-1225 2050);
DISPLAY 0.617021 (-1225 2050);
PAINT AQUA (-1225 2050);
DISPLAY INVISIBLE (-1225 2050);
FORCEPROP 1 LAST PATH I89
J 0
(-1225 2100);
DISPLAY 0.978723 (-1225 2100);
PAINT BLUE (-1225 2100);
DISPLAY INVISIBLE (-1225 2100);
FORCEPROP 2 LAST ROOM PROC_SIDEBAND
J 0
(-1425 2090);
DISPLAY 0.787234 (-1425 2090);
PAINT SKYBLUE (-1425 2090);
DISPLAY INVISIBLE (-1425 2090);
FORCEADD OFFPAGE..2
(2450 4250);
FORCEPROP 2 LAST $XR1 191 
J 0
(2759 4250);
DISPLAY 0.638298 (2759 4250);
PAINT MONO (2759 4250);
FORCEPROP 2 LAST $XR0 156 
J 0
(2639 4250);
DISPLAY 0.638298 (2639 4250);
PAINT MONO (2639 4250);
FORCEPROP 2 LAST CDS_LIB mstr_standard
J 1
(2450 4250);
PAINT ORANGE (2450 4250);
DISPLAY INVISIBLE (2450 4250);
FORCEPROP 2 LAST ROOM DIMM_EVENT
J 0
(2650 4300);
PAINT MONO (2650 4300);
DISPLAY INVISIBLE (2650 4300);
FORCEPROP 2 LAST PATH I90
J 0
(3000 4300);
DISPLAY 1.021277 (3000 4300);
PAINT ORANGE (3000 4300);
DISPLAY INVISIBLE (3000 4300);
FORCEPROP 1 LAST OFFPAGE TRUE
J 0
(2775 4125);
PAINT GREEN (2775 4125);
DISPLAY INVISIBLE (2775 4125);
FORCEPROP 1 LAST COMMENT_BODY TRUE
J 0
(2405 4155);
DISPLAY 1.170213 (2405 4155);
PAINT GREEN (2405 4155);
DISPLAY INVISIBLE (2405 4155);
FORCEADD RES..2
R 2
(1400 4450);
FORCEPROP 1 LASTPIN (1400 4550) $PN 1
J 2
(1395 4512);
DISPLAY 0.617021 (1395 4512);
PAINT MONO (1395 4512);
FORCEPROP 1 LASTPIN (1400 4350) $PN 2
J 2
(1395 4360);
DISPLAY 0.617021 (1395 4360);
PAINT MONO (1395 4360);
FORCEPROP 1 LAST LOCATION R4U1
J 0
(1455 4575);
DISPLAY 0.617021 (1455 4575);
PAINT AQUA (1455 4575);
FORCEPROP 1 LAST VALUE 4.75K
J 0
(1455 4525);
DISPLAY 0.617021 (1455 4525);
PAINT SKYBLUE (1455 4525);
FORCEPROP 1 LAST TOLERANCE 1%
J 0
(1455 4475);
DISPLAY 0.617021 (1455 4475);
PAINT SKYBLUE (1455 4475);
FORCEPROP 1 LAST WATTAGE 1/16W
J 0
(1460 4425);
DISPLAY 0.617021 (1460 4425);
PAINT SKYBLUE (1460 4425);
FORCEPROP 1 LAST PART_NUMBER G21796-072
J 0
(1460 4375);
DISPLAY 0.617021 (1460 4375);
PAINT BLUE (1460 4375);
FORCEPROP 1 LAST MATERIAL CHIP
J 0
(1460 4325);
DISPLAY 0.617021 (1460 4325);
PAINT SKYBLUE (1460 4325);
FORCEPROP 1 LAST PACK_TYPE 0402
J 0
(1460 4275);
DISPLAY 0.617021 (1460 4275);
PAINT SKYBLUE (1460 4275);
FORCEPROP 2 LAST CDS_LOCATION R4U1
J 2
(1355 4575);
DISPLAY 0.617021 (1355 4575);
PAINT AQUA (1355 4575);
DISPLAY INVISIBLE (1355 4575);
FORCEPROP 2 LAST SEC 1
J 0
(1350 4675);
DISPLAY 0.680851 (1350 4675);
PAINT MONO (1350 4675);
DISPLAY INVISIBLE (1350 4675);
FORCEPROP 2 LAST SEC_TYPE 0402
J 0
(1350 4675);
DISPLAY 1.021277 (1350 4675);
PAINT ORANGE (1350 4675);
DISPLAY INVISIBLE (1350 4675);
FORCEPROP 2 LAST CDS_LIB mstr_discrete
J 2
(1400 4450);
PAINT ORANGE (1400 4450);
DISPLAY INVISIBLE (1400 4450);
FORCEPROP 2 LAST BOM_COST PROC_SIDEBAND
J 0
(1400 4450);
PAINT MONO (1400 4450);
DISPLAY INVISIBLE (1400 4450);
FORCEPROP 1 LAST PATH I91
J 0
(1350 4625);
DISPLAY 0.978723 (1350 4625);
PAINT WHITE (1350 4625);
DISPLAY INVISIBLE (1350 4625);
FORCEPROP 2 LAST ROOM PROC_SIDEBAND
J 0
(1375 4225);
PAINT ORANGE (1375 4225);
DISPLAY INVISIBLE (1375 4225);
FORCEADD P3V3_STBY..1
(1400 4700);
FORCEPROP 3 LASTPIN (1400 4650) SIG_NAME P3V3_STBY\g
J 0
(1410 4660);
DISPLAY 0.659574 (1410 4660);
PAINT MONO (1410 4660);
DISPLAY INVISIBLE (1410 4660);
FORCEPROP 1 LAST VOLTAGE 3.3V
J 0
(1355 4657);
DISPLAY 0.340426 (1355 4657);
PAINT SKYBLUE (1355 4657);
DISPLAY INVISIBLE (1355 4657);
FORCEPROP 1 LAST SIZE 1B
J 0
(1445 4722);
DISPLAY 0.340426 (1445 4722);
PAINT GREEN (1445 4722);
DISPLAY INVISIBLE (1445 4722);
FORCEPROP 2 LAST CDS_LIB mstr_symbols
J 0
(1400 4700);
PAINT ORANGE (1400 4700);
DISPLAY INVISIBLE (1400 4700);
FORCEPROP 1 LAST PATH I92
J 0
(1445 4702);
DISPLAY 0.340426 (1445 4702);
PAINT GREEN (1445 4702);
DISPLAY INVISIBLE (1445 4702);
FORCEPROP 1 LAST BODY_TYPE PLUMBING
J 0
(1355 4657);
DISPLAY 0.340426 (1355 4657);
PAINT GREEN (1355 4657);
DISPLAY INVISIBLE (1355 4657);
FORCEPROP 1 LAST HDL_POWER P3V3_STBY
J 0
(1100 4575);
DISPLAY 0.872340 (1100 4575);
PAINT ORANGE (1100 4575);
DISPLAY INVISIBLE (1100 4575);
FORCEADD RES..2
R 2
(175 4075);
FORCEPROP 1 LAST LOCATION R4U3
J 2
(130 4200);
DISPLAY 0.617021 (130 4200);
PAINT AQUA (130 4200);
FORCEPROP 1 LAST PART_NUMBER G21796-072
J 2
(135 4000);
DISPLAY 0.617021 (135 4000);
PAINT BLUE (135 4000);
FORCEPROP 1 LAST VALUE 4.75K
J 2
(130 4150);
DISPLAY 0.617021 (130 4150);
PAINT SKYBLUE (130 4150);
FORCEPROP 1 LAST TOLERANCE 1%
J 2
(130 4100);
DISPLAY 0.617021 (130 4100);
PAINT SKYBLUE (130 4100);
FORCEPROP 1 LAST PACK_TYPE 0402
J 2
(135 3900);
DISPLAY 0.617021 (135 3900);
PAINT SKYBLUE (135 3900);
FORCEPROP 1 LAST WATTAGE 1/16W
J 2
(135 4050);
DISPLAY 0.617021 (135 4050);
PAINT SKYBLUE (135 4050);
FORCEPROP 1 LASTPIN (175 3975) $PN 2
J 2
(170 3985);
DISPLAY 0.617021 (170 3985);
PAINT MONO (170 3985);
FORCEPROP 1 LASTPIN (175 4175) $PN 1
J 2
(170 4137);
DISPLAY 0.617021 (170 4137);
PAINT MONO (170 4137);
FORCEPROP 1 LAST MATERIAL CHIP
J 2
(135 3950);
DISPLAY 0.617021 (135 3950);
PAINT SKYBLUE (135 3950);
FORCEPROP 2 LAST SEC_TYPE 0402
J 0
(125 4300);
DISPLAY 1.021277 (125 4300);
PAINT ORANGE (125 4300);
DISPLAY INVISIBLE (125 4300);
FORCEPROP 2 LAST BOM_COST PROC_SIDEBAND
J 2
(175 4075);
PAINT MONO (175 4075);
DISPLAY INVISIBLE (175 4075);
FORCEPROP 2 LAST CDS_LIB mstr_discrete
J 2
(175 4075);
PAINT ORANGE (175 4075);
DISPLAY INVISIBLE (175 4075);
FORCEPROP 2 LAST SEC 1
J 0
(125 4300);
DISPLAY 0.680851 (125 4300);
PAINT MONO (125 4300);
DISPLAY INVISIBLE (125 4300);
FORCEPROP 2 LAST CDS_LOCATION R4U3
J 2
(130 4200);
DISPLAY 0.617021 (130 4200);
PAINT AQUA (130 4200);
DISPLAY INVISIBLE (130 4200);
FORCEPROP 1 LAST PATH I94
J 2
(125 4250);
DISPLAY 0.978723 (125 4250);
PAINT WHITE (125 4250);
DISPLAY INVISIBLE (125 4250);
FORCEPROP 2 LAST ROOM PROC_SIDEBAND
J 2
(150 3850);
PAINT ORANGE (150 3850);
DISPLAY INVISIBLE (150 3850);
FORCEADD GND..1
(1400 3550);
FORCEPROP 3 LASTPIN (1400 3600) SIG_NAME GND\g
J 0
(1410 3610);
DISPLAY 0.659574 (1410 3610);
PAINT MONO (1410 3610);
DISPLAY INVISIBLE (1410 3610);
FORCEPROP 1 LAST VOLTAGE 0
J 0
(1400 3550);
PAINT SKYBLUE (1400 3550);
DISPLAY INVISIBLE (1400 3550);
FORCEPROP 2 LAST CDS_LIB mstr_symbols
J 0
(1400 3550);
DISPLAY 1.765957 (1400 3550);
PAINT ORANGE (1400 3550);
DISPLAY INVISIBLE (1400 3550);
FORCEPROP 1 LAST SIZE 1B
J 0
(1475 3500);
DISPLAY 0.978723 (1475 3500);
PAINT GREEN (1475 3500);
DISPLAY INVISIBLE (1475 3500);
FORCEPROP 2 LAST BOM_COST DEBUG
J 0
(1250 3625);
PAINT MONO (1250 3625);
DISPLAY INVISIBLE (1250 3625);
FORCEPROP 1 LAST PATH I95
J 0
(1475 3550);
DISPLAY 0.872340 (1475 3550);
PAINT AQUA (1475 3550);
DISPLAY INVISIBLE (1475 3550);
FORCEPROP 2 LAST ROOM SYSTEM_DEBUG_LEDS
J 0
(1050 3625);
DISPLAY 0.978723 (1050 3625);
PAINT ORANGE (1050 3625);
DISPLAY INVISIBLE (1050 3625);
FORCEPROP 1 LAST BODY_TYPE PLUMBING
J 0
(1355 3507);
DISPLAY 0.340426 (1355 3507);
PAINT GREEN (1355 3507);
DISPLAY INVISIBLE (1355 3507);
FORCEPROP 1 LAST HDL_POWER GND
J 0
(1400 3700);
DISPLAY 0.978723 (1400 3700);
PAINT GREEN (1400 3700);
DISPLAY INVISIBLE (1400 3700);
FORCEADD GND..1
(175 3225);
FORCEPROP 3 LASTPIN (175 3275) SIG_NAME GND\g
J 0
(185 3285);
DISPLAY 0.659574 (185 3285);
PAINT MONO (185 3285);
DISPLAY INVISIBLE (185 3285);
FORCEPROP 1 LAST VOLTAGE 0
J 0
(175 3225);
PAINT SKYBLUE (175 3225);
DISPLAY INVISIBLE (175 3225);
FORCEPROP 1 LAST SIZE 1B
J 0
(250 3175);
DISPLAY 1.170213 (250 3175);
PAINT GREEN (250 3175);
DISPLAY INVISIBLE (250 3175);
FORCEPROP 2 LAST CDS_LIB mstr_symbols
J 0
(175 3225);
PAINT MONO (175 3225);
DISPLAY INVISIBLE (175 3225);
FORCEPROP 1 LAST PATH I97
J 0
(250 3225);
DISPLAY 0.872340 (250 3225);
PAINT AQUA (250 3225);
DISPLAY INVISIBLE (250 3225);
FORCEPROP 1 LAST BODY_TYPE PLUMBING
J 0
(130 3182);
DISPLAY 0.340426 (130 3182);
PAINT GREEN (130 3182);
DISPLAY INVISIBLE (130 3182);
FORCEPROP 1 LAST HDL_POWER GND
J 0
(175 3375);
DISPLAY 1.170213 (175 3375);
PAINT GREEN (175 3375);
DISPLAY INVISIBLE (175 3375);
FORCEADD FET_N_DUAL..5
(175 3525);
FORCEPROP 1 LASTPIN (175 3325) $PN 1
J 2
(233 3325);
DISPLAY 0.617021 (233 3325);
PAINT WHITE (233 3325);
FORCEPROP 1 LASTPIN (-25 3425) $PN 2
J 2
(-22 3440);
DISPLAY 0.617021 (-22 3440);
PAINT WHITE (-22 3440);
FORCEPROP 1 LASTPIN (175 3725) $PN 6
J 2
(228 3690);
DISPLAY 0.617021 (228 3690);
PAINT WHITE (228 3690);
FORCEPROP 1 LAST VALUE NTJD4001N
J 0
(350 3475);
DISPLAY 0.617021 (350 3475);
PAINT SKYBLUE (350 3475);
FORCEPROP 1 LAST MATERIAL FET
J 0
(350 3425);
DISPLAY 0.617021 (350 3425);
PAINT SKYBLUE (350 3425);
FORCEPROP 1 LAST LOCATION Q4U1
J 0
(350 3575);
DISPLAY 0.617021 (350 3575);
PAINT AQUA (350 3575);
FORCEPROP 1 LAST PART_NUMBER E40049-001
J 0
(350 3525);
DISPLAY 0.617021 (350 3525);
PAINT BLUE (350 3525);
FORCEPROP 1 LAST PACK_TYPE SMLF
J 0
(375 3375);
PAINT SKYBLUE (375 3375);
DISPLAY INVISIBLE (375 3375);
FORCEPROP 2 LAST CDS_LIB mstr_discrete
J 0
(175 3525);
PAINT ORANGE (175 3525);
DISPLAY INVISIBLE (175 3525);
FORCEPROP 2 LAST SEC_TYPE SMLF
J 0
(-225 3775);
DISPLAY 1.021277 (-225 3775);
PAINT ORANGE (-225 3775);
DISPLAY INVISIBLE (-225 3775);
FORCEPROP 2 LAST BOM_COST PROC_SIDEBAND
J 0
(175 3525);
PAINT MONO (175 3525);
DISPLAY INVISIBLE (175 3525);
FORCEPROP 2 LAST SEC 1
J 0
(-225 3775);
DISPLAY 0.680851 (-225 3775);
PAINT MONO (-225 3775);
DISPLAY INVISIBLE (-225 3775);
FORCEPROP 2 LAST CDS_LOCATION Q4U1
J 0
(375 3525);
DISPLAY 0.617021 (375 3525);
PAINT AQUA (375 3525);
DISPLAY INVISIBLE (375 3525);
FORCEPROP 1 LAST PATH I98
J 0
(375 3575);
DISPLAY 0.978723 (375 3575);
PAINT BLUE (375 3575);
DISPLAY INVISIBLE (375 3575);
FORCEPROP 2 LAST ROOM PROC_SIDEBAND
J 0
(375 3625);
PAINT ORANGE (375 3625);
DISPLAY INVISIBLE (375 3625);
FORCEADD PVPP_ABC..1
(-300 4050);
FORCEPROP 3 LASTPIN (-300 4000) SIG_NAME PVPP_ABC\g
J 0
(-290 4010);
DISPLAY 0.659574 (-290 4010);
PAINT MONO (-290 4010);
DISPLAY INVISIBLE (-290 4010);
FORCEPROP 1 LAST VOLTAGE 2.5V
J 0
(-345 4007);
DISPLAY 0.340426 (-345 4007);
PAINT SKYBLUE (-345 4007);
DISPLAY INVISIBLE (-345 4007);
FORCEPROP 2 LAST BOM_COST PVPP_KLM_VR
J 0
(-225 4150);
PAINT MONO (-225 4150);
DISPLAY INVISIBLE (-225 4150);
FORCEPROP 2 LAST CDS_LIB mstr_symbols
J 0
(-300 4050);
PAINT ORANGE (-300 4050);
DISPLAY INVISIBLE (-300 4050);
FORCEPROP 1 LAST PATH I99
J 0
(-250 4075);
DISPLAY 0.872340 (-250 4075);
PAINT AQUA (-250 4075);
DISPLAY INVISIBLE (-250 4075);
FORCEPROP 2 LAST ROOM PVPP_KLM_VR
J 0
(-50 4150);
PAINT ORANGE (-50 4150);
DISPLAY INVISIBLE (-50 4150);
FORCEPROP 1 LAST BODY_TYPE PLUMBING
J 0
(-345 4007);
DISPLAY 0.340426 (-345 4007);
PAINT GREEN (-345 4007);
DISPLAY INVISIBLE (-345 4007);
FORCEPROP 1 LAST HDL_POWER PVPP_ABC
J 1
(-300 4100);
DISPLAY 0.872340 (-300 4100);
PAINT GREEN (-300 4100);
DISPLAY INVISIBLE (-300 4100);
FORCEADD INTEL_CORP_BPAGE..1
(4250 25);
FORCEPROP 1 LAST CDS_CON_LAST_MODIFIED Fri Jun 16 17:48:35 2017
J 0
(2825 350);
PAINT ORANGE (2825 350);
DISPLAY INVISIBLE (2825 350);
FORCEPROP 1 LAST CUSTOM_TXT_CDS <CURRENT_DESIGN_SHEET> OF <TOTAL_DESIGN_SHEETS>
J 0
(3750 50);
PAINT ORANGE (3750 50);
FORCEPROP 1 LAST CUSTOM_TXT_CDS <CON_LAST_MODIFIED>
J 0
(250 125);
PAINT ORANGE (250 125);
FORCEPROP 2 LAST CUSTOM_TXT_CDS <XR_PAGE_TITLE>
J 0
(-3640 5275);
DISPLAY 0.638298 (-3640 5275);
PAINT PINK (-3640 5275);
DISPLAY INVISIBLE (-3640 5275);
FORCEPROP 1 LAST SCH_TITLE CPU SIDE BAND: PROCHOT & MEMHOT (1/2)
J 0
(-3700 75);
DISPLAY 1.212766 (-3700 75);
PAINT ORANGE (-3700 75);
FORCEPROP 2 LAST CDS_LIB mstr_symbols
J 0
(4250 25);
PAINT MONO (4250 25);
DISPLAY INVISIBLE (4250 25);
FORCEPROP 2 LAST PAGE_BORDER TRUE
J 0
(-3640 5275);
DISPLAY 0.638298 (-3640 5275);
PAINT PINK (-3640 5275);
DISPLAY INVISIBLE (-3640 5275);
FORCEPROP 1 LAST COMMENT_BODY TRUE
J 0
(4262 37);
DISPLAY 0.468085 (4262 37);
PAINT GREEN (4262 37);
DISPLAY INVISIBLE (4262 37);
FORCEPROP 2 LAST CDS_XR_PAGE_TITLE CR-94 : @BASEBOARD_FAB2_LIB.BASEBOARD_FAB2(SCH_1):PAGE94
J 0
(-3640 5275);
DISPLAY 0.638298 (-3640 5275);
PAINT PINK (-3640 5275);
DISPLAY INVISIBLE (-3640 5275);
WIRE 16 -1 (175 4175)(175 4250);
WIRE 16 -1 (750 3475)(750 3275);
WIRE 16 -1 (-1425 1850)(-1425 1800);
WIRE 16 -1 (-2150 2525)(-2150 2475);
WIRE 16 -1 (-2150 1725)(-2150 1700);
WIRE 16 -1 (-1425 750)(-1425 700);
WIRE 16 -1 (-2150 1425)(-2150 1375);
WIRE 16 -1 (-2150 625)(-2150 600);
WIRE 16 -1 (1900 1900)(1900 1850);
WIRE 16 -1 (1900 800)(1900 750);
WIRE 16 -1 (1175 2575)(1175 2525);
WIRE 16 -1 (1175 1775)(1175 1750);
WIRE 16 -1 (1175 1475)(1175 1425);
WIRE 16 -1 (1175 675)(1175 650);
WIRE 16 -1 (1400 4550)(1400 4650);
WIRE 16 -1 (1400 3750)(1400 3600);
WIRE 16 -1 (175 3275)(175 3325);
WIRE 16 -1 (-300 4000)(-300 3750);
WIRE 16 273 (4125 2725)(-3700 2725);
WIRE 16 -1 (1900 1200)(1900 1250);
WIRE 16 -1 (1900 1250)(2600 1250);
FORCEPROP 2 LAST SIG_NAME H_CPU1_MEMKLM_MEMHOT_G_N
J 0
(1923 1260);
DISPLAY 0.617021 (1923 1260);
PAINT ORANGE (1923 1260);
WIRE 16 -1 (1900 2300)(1900 2350);
WIRE 16 -1 (1900 2350)(2600 2350);
FORCEPROP 2 LAST SIG_NAME H_CPU1_MEMGHJ_MEMHOT_G_N
J 0
(1923 2360);
DISPLAY 0.617021 (1923 2360);
PAINT ORANGE (1923 2360);
WIRE 16 -1 (1650 2000)(1700 2000);
WIRE 16 -1 (1175 2175)(1175 2200);
WIRE 16 -1 (1175 2200)(1175 2325);
WIRE 16 -1 (1650 2200)(1650 2000);
WIRE 16 -1 (1650 2200)(1175 2200);
FORCEPROP 0 LAST SIG_NAME H_CPU1_MEMGHJ_MEMHOT
J 0
(1240 2210);
DISPLAY 0.617021 (1240 2210);
PAINT ORANGE (1240 2210);
FORCEPROP 2 LASTPROP $XRERR UNIQUE?
J 0
(1000 2210);
DISPLAY 0.638298 (1000 2210);
PAINT MONO (1000 2210);
DISPLAY INVISIBLE (1000 2210);
WIRE 16 -1 (1650 900)(1700 900);
WIRE 16 -1 (1175 1075)(1175 1100);
WIRE 16 -1 (1175 1100)(1175 1225);
WIRE 16 -1 (1650 1100)(1650 900);
WIRE 16 -1 (1650 1100)(1175 1100);
FORCEPROP 0 LAST SIG_NAME H_CPU1_MEMKLM_MEMHOT
J 0
(1240 1110);
DISPLAY 0.617021 (1240 1110);
PAINT ORANGE (1240 1110);
FORCEPROP 2 LASTPROP $XRERR UNIQUE?
J 0
(1000 1110);
DISPLAY 0.638298 (1000 1110);
PAINT MONO (1000 1110);
DISPLAY INVISIBLE (1000 1110);
WIRE 16 -1 (50 1875)(975 1875);
FORCEPROP 0 LAST SIG_NAME IRQ_PVDDQ_GHJ_VRHOT_LVT3_N
J 0
(40 1885);
DISPLAY 0.617021 (40 1885);
PAINT ORANGE (40 1885);
WIRE 16 -1 (50 775)(975 775);
FORCEPROP 0 LAST SIG_NAME IRQ_PVDDQ_KLM_VRHOT_LVT3_N
J 0
(40 785);
DISPLAY 0.617021 (40 785);
PAINT ORANGE (40 785);
WIRE 16 -1 (-1425 1150)(-1425 1200);
WIRE 16 -1 (-1425 1200)(-725 1200);
FORCEPROP 2 LAST SIG_NAME H_CPU0_MEMDEF_MEMHOT_G_N
J 0
(-1402 1210);
DISPLAY 0.617021 (-1402 1210);
PAINT ORANGE (-1402 1210);
WIRE 16 -1 (-2150 1025)(-2150 1050);
WIRE 16 -1 (-2150 1050)(-2150 1175);
WIRE 16 -1 (-1675 850)(-1625 850);
WIRE 16 -1 (-1675 1050)(-2150 1050);
FORCEPROP 0 LAST SIG_NAME H_CPU0_MEMDEF_MEMHOT
J 0
(-2085 1060);
DISPLAY 0.617021 (-2085 1060);
PAINT ORANGE (-2085 1060);
FORCEPROP 2 LASTPROP $XRERR UNIQUE?
J 0
(-2325 1060);
DISPLAY 0.638298 (-2325 1060);
PAINT MONO (-2325 1060);
DISPLAY INVISIBLE (-2325 1060);
WIRE 16 -1 (-1675 1050)(-1675 850);
WIRE 16 -1 (-3275 725)(-2350 725);
FORCEPROP 0 LAST SIG_NAME IRQ_PVDDQ_DEF_VRHOT_LVT3_N
J 0
(-3285 735);
DISPLAY 0.617021 (-3285 735);
PAINT ORANGE (-3285 735);
WIRE 16 -1 (-3275 1825)(-2350 1825);
FORCEPROP 0 LAST SIG_NAME IRQ_PVDDQ_ABC_VRHOT_LVT3_N
J 0
(-3285 1835);
DISPLAY 0.617021 (-3285 1835);
PAINT ORANGE (-3285 1835);
WIRE 16 -1 (1400 4150)(1400 4250);
WIRE 16 -1 (1400 4250)(2400 4250);
FORCEPROP 2 LAST SIG_NAME FM_MEM_THERM_EVENT_LVT3_N
J 0
(1690 4260);
DISPLAY 0.617021 (1690 4260);
PAINT ORANGE (1690 4260);
WIRE 16 -1 (1400 4350)(1400 4250);
WIRE 16 -1 (750 3675)(750 3850);
WIRE 16 -1 (750 3850)(1200 3850);
WIRE 16 -1 (175 3725)(175 3850);
WIRE 16 -1 (175 3850)(750 3850);
FORCEPROP 2 LAST SIG_NAME FM_DIMM_EVENT_FET
J 0
(365 3860);
DISPLAY 0.617021 (365 3860);
PAINT ORANGE (365 3860);
FORCEPROP 2 LASTPROP $XRERR UNIQUE?
J 0
(125 3860);
DISPLAY 0.638298 (125 3860);
PAINT MONO (125 3860);
DISPLAY INVISIBLE (125 3860);
WIRE 16 -1 (175 3975)(175 3850);
WIRE 16 -1 (-1425 2250)(-1425 2300);
WIRE 16 -1 (-1425 2300)(-725 2300);
FORCEPROP 2 LAST SIG_NAME H_CPU0_MEMABC_MEMHOT_G_N
J 0
(-1402 2310);
DISPLAY 0.617021 (-1402 2310);
PAINT ORANGE (-1402 2310);
WIRE 16 -1 (-2150 2125)(-2150 2150);
WIRE 16 -1 (-2150 2150)(-2150 2275);
WIRE 16 -1 (-1675 1950)(-1625 1950);
WIRE 16 -1 (-1675 2150)(-2150 2150);
FORCEPROP 0 LAST SIG_NAME H_CPU0_MEMABC_MEMHOT
J 0
(-2085 2160);
DISPLAY 0.617021 (-2085 2160);
PAINT ORANGE (-2085 2160);
FORCEPROP 2 LASTPROP $XRERR UNIQUE?
J 0
(-2325 2160);
DISPLAY 0.638298 (-2325 2160);
PAINT MONO (-2325 2160);
DISPLAY INVISIBLE (-2325 2160);
WIRE 16 -1 (-1675 2150)(-1675 1950);
WIRE 16 -1 (-25 3425)(-300 3425);
WIRE 16 -1 (-300 3550)(-300 3425);
WIRE 16 -1 (-1600 3425)(-300 3425);
FORCEPROP 2 LAST SIG_NAME FM_DIMM_EVENT_COD_N
J 0
(-1585 3435);
DISPLAY 0.617021 (-1585 3435);
PAINT ORANGE (-1585 3435);
DOT 1 (1400 4250);
DOT 1 (1175 1100);
DOT 1 (1175 2200);
DOT 1 (-2150 1050);
DOT 1 (-2150 2150);
DOT 1 (-300 3425);
DOT 1 (750 3850);
DOT 1 (175 3850);
FORCENOTE
ROOM=PROC_SIDEBAND
(-3684 186) 0;
DISPLAY LEFT (-3684 186);
DISPLAY 1.276596 (-3684 186);
PAINT PURPLE (-3684 186);
QUIT
